G04 ================== begin FILE IDENTIFICATION RECORD ==================*
G04 Layout Name:  x887571-005_osp.brd*
G04 Film Name:    ssb*
G04 File Format:  Gerber RS274X*
G04 File Origin:  Cadence Allegro 16.3-S036*
G04 Origin Date:  Thu Jul 03 00:06:57 2014*
G04 *
G04 Layer:  REF DES/SILKSCREEN_BOTTOM*
G04 Layer:  PACKAGE GEOMETRY/SILKSCREEN_BOTTOM*
G04 Layer:  DRAWING FORMAT/COMMON TEXT*
G04 Layer:  BOARD GEOMETRY/SILKSCREEN_BOTTOM*
G04 *
G04 Offset:    (0.0000 0.0000)*
G04 Mirror:    No*
G04 Mode:      Positive*
G04 Rotation:  0*
G04 FullContactRelief:  No*
G04 UndefLineWidth:     4.0000*
G04 ================== end FILE IDENTIFICATION RECORD ====================*
%FSLAX25Y25*MOIN*%
%IR0*IPPOS*OFA0.00000B0.00000*MIA0B0*SFA1.00000B1.00000*%
%ADD10C,.01*%
%ADD11C,.012*%
%ADD12C,.013*%
%ADD13C,.015*%
%ADD14C,.004*%
%ADD15C,.005*%
%ADD16C,.006*%
%ADD17C,.007*%
%ADD18C,.008*%
G75*
%LPD*%
G75*
G54D10*
G01X-1184000Y-502500D02*
Y-512500D01*
G01X-1186683Y-502500D02*
X-1181317D01*
G01X-1176833Y-512500D02*
Y-502500D01*
X-1173917D01*
X-1172983Y-503000D01*
X-1172400Y-503667D01*
X-1172167Y-505000D01*
X-1172400Y-506333D01*
X-1173100Y-507167D01*
X-1173917Y-507667D01*
X-1176833D01*
G01X-1173917D02*
X-1172167Y-512500D01*
G01X-1167917D02*
X-1165000Y-502500D01*
X-1162083Y-512500D01*
G01X-1163133Y-509000D02*
X-1166867D01*
G01X-1155500Y-512500D02*
Y-508000D01*
X-1157833Y-502500D01*
G01X-1153167D02*
X-1155500Y-508000D01*
G01X-1135567Y-507167D02*
X-1135100Y-506667D01*
X-1134750Y-505834D01*
X-1134517Y-504667D01*
X-1134750Y-503667D01*
X-1135217Y-503000D01*
X-1136033Y-502500D01*
X-1139183D01*
Y-512500D01*
X-1135333D01*
X-1134517Y-511833D01*
X-1134050Y-510833D01*
X-1133817Y-509667D01*
X-1134050Y-508500D01*
X-1134750Y-507500D01*
X-1135567Y-507167D01*
X-1139183D01*
G01X-1129917Y-512500D02*
X-1127000Y-502500D01*
X-1124083Y-512500D01*
G01X-1125133Y-509000D02*
X-1128867D01*
G01X-1114933Y-503333D02*
X-1115633Y-502833D01*
X-1116450Y-502500D01*
X-1117383D01*
X-1118433Y-503000D01*
X-1119250Y-503833D01*
X-1119833Y-504833D01*
X-1120300Y-506500D01*
X-1120417Y-508000D01*
X-1120183Y-509500D01*
X-1119833Y-510500D01*
X-1119133Y-511500D01*
X-1118317Y-512167D01*
X-1117500Y-512500D01*
X-1116683D01*
X-1115867Y-512167D01*
X-1115167Y-511667D01*
X-1114583Y-511000D01*
G01X-1110567Y-512500D02*
Y-502500D01*
G01X-1106133D02*
X-1110567Y-508667D01*
G01X-1105433Y-512500D02*
X-1108583Y-505834D01*
G01X-1100833Y-512500D02*
Y-502500D01*
X-1098033D01*
X-1097100Y-503000D01*
X-1096400Y-504167D01*
X-1096167Y-505500D01*
X-1096400Y-506833D01*
X-1096983Y-507833D01*
X-1098033Y-508334D01*
X-1100833D01*
G01X-1091333Y-502500D02*
Y-512500D01*
X-1086667D01*
G01X-1082417D02*
X-1079500Y-502500D01*
X-1076583Y-512500D01*
G01X-1077633Y-509000D02*
X-1081367D01*
G01X-1072683Y-512500D02*
Y-502500D01*
X-1067317Y-512500D01*
Y-502500D01*
G01X-1058167Y-512500D02*
X-1062833D01*
Y-502500D01*
X-1058167D01*
G01X-1060033Y-507333D02*
X-1062833D01*
G01X-1043717Y-512500D02*
Y-502500D01*
X-1039283D01*
G01X-1040917Y-507333D02*
X-1043717D01*
G01X-1034917Y-512500D02*
X-1032000Y-502500D01*
X-1029083Y-512500D01*
G01X-1030133Y-509000D02*
X-1033867D01*
G01X-1021567Y-507167D02*
X-1021100Y-506667D01*
X-1020750Y-505834D01*
X-1020517Y-504667D01*
X-1020750Y-503667D01*
X-1021217Y-503000D01*
X-1022033Y-502500D01*
X-1025183D01*
Y-512500D01*
X-1021333D01*
X-1020517Y-511833D01*
X-1020050Y-510833D01*
X-1019817Y-509667D01*
X-1020050Y-508500D01*
X-1020750Y-507500D01*
X-1021567Y-507167D01*
X-1025183D01*
G01X-1002567D02*
X-1002100Y-506667D01*
X-1001750Y-505834D01*
X-1001517Y-504667D01*
X-1001750Y-503667D01*
X-1002217Y-503000D01*
X-1003033Y-502500D01*
X-1006183D01*
Y-512500D01*
X-1002333D01*
X-1001517Y-511833D01*
X-1001050Y-510833D01*
X-1000817Y-509667D01*
X-1001050Y-508500D01*
X-1001750Y-507500D01*
X-1002567Y-507167D01*
X-1006183D01*
G01X-985083Y-515833D02*
X-986250Y-514167D01*
X-986833Y-512500D01*
Y-505834D01*
X-986250Y-504167D01*
X-985083Y-502500D01*
G01X-975000Y-512500D02*
X-975933Y-512333D01*
X-976750Y-511667D01*
X-977450Y-510667D01*
X-977917Y-509500D01*
X-978150Y-508167D01*
Y-506833D01*
X-977917Y-505500D01*
X-977450Y-504333D01*
X-976750Y-503333D01*
X-975933Y-502667D01*
X-975000Y-502500D01*
X-974067Y-502667D01*
X-973250Y-503333D01*
X-972550Y-504333D01*
X-972083Y-505500D01*
X-971850Y-506833D01*
Y-508167D01*
X-972083Y-509500D01*
X-972550Y-510667D01*
X-973250Y-511667D01*
X-974067Y-512333D01*
X-975000Y-512500D01*
G01X-967950Y-511167D02*
X-967017Y-512000D01*
X-965967Y-512500D01*
X-965033D01*
X-964100Y-512000D01*
X-963400Y-511167D01*
X-963050Y-510000D01*
X-963283Y-508834D01*
X-963867Y-507833D01*
X-964917Y-507167D01*
X-966317Y-506833D01*
X-967133Y-506167D01*
X-967483Y-505000D01*
X-967250Y-503833D01*
X-966667Y-503000D01*
X-965850Y-502500D01*
X-965033D01*
X-964217Y-502833D01*
X-963517Y-503667D01*
G01X-958333Y-512500D02*
Y-502500D01*
X-955533D01*
X-954600Y-503000D01*
X-953900Y-504167D01*
X-953667Y-505500D01*
X-953900Y-506833D01*
X-954483Y-507833D01*
X-955533Y-508334D01*
X-958333D01*
G01X-945917Y-515833D02*
X-944750Y-514167D01*
X-944167Y-512500D01*
Y-505834D01*
X-944750Y-504167D01*
X-945917Y-502500D01*
G01X-902000Y-470000D02*
Y-460000D01*
X-903400Y-462000D01*
G01Y-470000D02*
X-900600D01*
G01X-892500Y-470333D02*
X-892733Y-470167D01*
Y-469833D01*
X-892500Y-469667D01*
X-892267Y-469833D01*
Y-470167D01*
X-892500Y-470333D01*
G01Y-465834D02*
X-892733Y-465667D01*
Y-465333D01*
X-892500Y-465167D01*
X-892267Y-465333D01*
Y-465667D01*
X-892500Y-465834D01*
G01X-883000Y-470000D02*
Y-460000D01*
X-884400Y-462000D01*
G01Y-470000D02*
X-881600D01*
G01X-785060Y-472187D02*
X-784127Y-473020D01*
X-783077Y-473520D01*
X-782143D01*
X-781210Y-473020D01*
X-780510Y-472187D01*
X-780160Y-471020D01*
X-780393Y-469854D01*
X-780977Y-468853D01*
X-782027Y-468187D01*
X-783427Y-467853D01*
X-784243Y-467187D01*
X-784593Y-466020D01*
X-784360Y-464853D01*
X-783777Y-464020D01*
X-782960Y-463520D01*
X-782143D01*
X-781327Y-463853D01*
X-780627Y-464687D01*
G01X-775560Y-473520D02*
Y-463520D01*
G01X-770660D02*
Y-473520D01*
G01Y-468520D02*
X-775560D01*
G01X-766527Y-473520D02*
X-763610Y-463520D01*
X-760693Y-473520D01*
G01X-761743Y-470020D02*
X-765477D01*
G01X-757610Y-463520D02*
X-755977Y-473520D01*
X-754110Y-463520D01*
X-752243Y-473520D01*
X-750610Y-463520D01*
G01X-668067Y-470500D02*
X-667367Y-471667D01*
X-666433Y-472333D01*
X-665383Y-472500D01*
X-664450Y-472333D01*
X-663517Y-471500D01*
X-662933Y-470500D01*
X-662817Y-469500D01*
X-663050Y-468334D01*
X-663867Y-467500D01*
X-664683Y-467167D01*
X-665733D01*
G01X-664683D02*
X-663983Y-466667D01*
X-663400Y-465834D01*
X-663167Y-464833D01*
X-663400Y-463833D01*
X-663983Y-463000D01*
X-665033Y-462500D01*
X-666083Y-462667D01*
X-667133Y-463333D01*
G01X-656000Y-462500D02*
X-656933Y-462833D01*
X-657633Y-463667D01*
X-658100Y-464667D01*
X-658450Y-466000D01*
X-658567Y-467500D01*
X-658450Y-469000D01*
X-658100Y-470333D01*
X-657633Y-471334D01*
X-656933Y-472167D01*
X-656000Y-472500D01*
X-655067Y-472167D01*
X-654367Y-471334D01*
X-653900Y-470333D01*
X-653550Y-469000D01*
X-653433Y-467500D01*
X-653550Y-466000D01*
X-653900Y-464667D01*
X-654367Y-463667D01*
X-655067Y-462833D01*
X-656000Y-462500D01*
G01X-648017Y-469167D02*
X-644983D01*
G01X-639917Y-472500D02*
X-637000Y-462500D01*
X-634083Y-472500D01*
G01X-635133Y-469000D02*
X-638867D01*
G01X-629833Y-472500D02*
Y-462500D01*
X-627033D01*
X-626100Y-463000D01*
X-625400Y-464167D01*
X-625167Y-465500D01*
X-625400Y-466833D01*
X-625983Y-467833D01*
X-627033Y-468334D01*
X-629833D01*
G01X-620333Y-472500D02*
Y-462500D01*
X-617417D01*
X-616483Y-463000D01*
X-615900Y-463667D01*
X-615667Y-465000D01*
X-615900Y-466333D01*
X-616600Y-467167D01*
X-617417Y-467667D01*
X-620333D01*
G01X-617417D02*
X-615667Y-472500D01*
G01X-610017Y-469167D02*
X-606983D01*
G01X-599000Y-472500D02*
Y-462500D01*
X-600400Y-464500D01*
G01Y-472500D02*
X-597600D01*
G01X-588100D02*
Y-462500D01*
X-592417Y-469667D01*
X-586583D01*
G54D11*
G01X-1174900Y-473500D02*
X-1171300Y-466100D01*
X-1171800Y-465700D01*
X-1175900Y-473200D01*
X-1176200Y-471200D01*
X-1172500Y-465400D01*
X-1175700Y-471300D01*
X-1176500Y-469800D01*
X-1172900Y-464900D01*
X-1173600Y-451800D01*
X-1173700Y-449900D01*
X-1182100D01*
X-1187400Y-473000D01*
X-1182400D01*
X-1177800Y-456000D01*
X-1177000Y-455900D01*
X-1176100Y-468500D01*
X-1173700Y-464500D01*
X-1174600Y-450800D01*
X-1181500Y-450900D01*
X-1186400Y-472100D01*
X-1183100D01*
X-1178300Y-454800D01*
X-1176600Y-455000D01*
X-1175500Y-466300D01*
X-1174600Y-464300D01*
X-1175400Y-451700D01*
X-1181000Y-451800D01*
X-1185300Y-471300D01*
X-1183800Y-471400D01*
X-1179000Y-454300D01*
X-1176200D01*
X-1175200Y-462200D01*
X-1176200Y-452500D01*
X-1180500Y-452800D01*
X-1184300Y-470600D01*
X-1179700Y-453400D01*
X-1176800D01*
G01X-1182820Y-448900D02*
X-1188360Y-473900D01*
X-1181580D01*
X-1177300Y-456700D01*
X-1176920Y-473900D01*
X-1172260D01*
X-1163400Y-456920D01*
X-1167240Y-473900D01*
X-1160380D01*
X-1154840Y-448900D01*
X-1164540D01*
X-1172540Y-464820D01*
X-1172880Y-448900D01*
X-1182820D01*
G01X-1155800Y-449500D02*
X-1161100Y-472900D01*
X-1166100Y-473000D01*
X-1166000Y-471900D01*
X-1161800Y-472100D01*
X-1161300Y-471000D01*
X-1165900Y-471100D01*
X-1165700Y-470000D01*
X-1161300D01*
X-1160800Y-469200D01*
X-1165300Y-469100D01*
X-1165200Y-468100D01*
X-1160700D01*
X-1160400Y-467100D01*
X-1165100Y-467200D01*
X-1164900Y-466300D01*
X-1160300Y-466200D01*
X-1160000Y-465200D01*
X-1164700Y-465300D01*
X-1164400Y-464200D01*
X-1159700Y-464300D01*
X-1159300Y-463100D01*
X-1164700Y-463500D01*
X-1164000Y-462500D01*
X-1159500Y-462600D01*
X-1159000Y-461700D01*
X-1163900D01*
X-1163600Y-460600D01*
X-1159100Y-460800D01*
X-1158800Y-459900D01*
X-1163200D01*
X-1163100Y-459200D01*
X-1158800D01*
X-1158300Y-458500D01*
X-1163000Y-458400D01*
X-1162900Y-457800D01*
X-1158400Y-457900D01*
X-1158200Y-457200D01*
X-1162500Y-457000D01*
X-1163100Y-456500D01*
X-1157800D01*
X-1157500Y-455500D01*
X-1156600Y-449800D01*
X-1164000D01*
X-1164500Y-450700D01*
X-1157600D01*
X-1157800Y-451700D01*
X-1165000Y-451600D01*
X-1165400Y-452400D01*
X-1157900Y-452500D01*
X-1157800Y-453500D01*
X-1165900Y-453200D01*
X-1166200Y-453900D01*
X-1158000Y-454300D01*
X-1158300Y-455300D01*
X-1166600Y-454800D01*
X-1158900Y-455900D01*
X-1167000Y-455600D01*
X-1163500Y-456400D01*
X-1167300Y-456300D01*
X-1171700Y-465200D01*
X-1169200Y-466400D01*
X-1164500Y-457200D01*
X-1166900Y-457100D01*
X-1170600Y-465200D01*
X-1169500Y-465500D01*
X-1166000Y-457800D01*
G01X-1170300Y-466300D02*
X-1174000Y-473600D01*
G01X-1169500Y-466900D02*
X-1172800Y-473000D01*
G01X-1152800Y-456400D02*
X-1156600Y-473100D01*
X-1152200Y-473000D01*
X-1148300Y-456600D01*
X-1149500D01*
X-1152900Y-472000D01*
X-1155600Y-472300D01*
X-1152100Y-456500D01*
X-1150400Y-456400D01*
X-1153600Y-471200D01*
X-1154500Y-471400D01*
X-1151400Y-457200D01*
G01X-1153420Y-455700D02*
X-1157540Y-473900D01*
X-1151380D01*
X-1147440Y-455700D01*
X-1153420D01*
G01X-1151600Y-450100D02*
X-1146700Y-450000D01*
X-1147000Y-451000D01*
X-1151700D01*
G01X-1152020Y-448900D02*
X-1152660Y-451900D01*
X-1146380D01*
X-1145740Y-448900D01*
X-1152020D01*
G01X-1129400Y-468900D02*
X-1131800Y-471900D01*
X-1136500Y-473700D01*
X-1142100Y-473600D01*
X-1144600Y-472300D01*
X-1145800Y-471000D01*
X-1146400Y-469500D01*
X-1146700Y-467600D01*
X-1146500Y-464600D01*
X-1145400Y-461200D01*
X-1143500Y-459100D01*
X-1140200Y-456900D01*
X-1136100Y-456200D01*
X-1132300Y-456400D01*
X-1129400Y-457900D01*
X-1127500Y-460900D01*
X-1132500Y-461000D01*
X-1133400Y-459200D01*
X-1135100Y-458100D01*
X-1136800Y-458000D01*
X-1138600Y-458900D01*
X-1140300Y-460700D01*
X-1141800Y-463600D01*
X-1142400Y-466600D01*
X-1141500Y-470400D01*
X-1140200Y-471500D01*
X-1138300Y-471600D01*
X-1136300Y-471400D01*
X-1134500Y-469100D01*
X-1130300Y-469000D01*
X-1132500Y-471200D01*
X-1134900Y-472000D01*
X-1137200Y-472800D01*
X-1142300Y-472700D01*
X-1144900Y-470600D01*
X-1145800Y-467400D01*
X-1145500Y-465100D01*
X-1144700Y-462000D01*
X-1143300Y-460200D01*
X-1139800Y-457700D01*
X-1135400Y-457000D01*
X-1131300Y-457600D01*
X-1128800Y-460100D01*
X-1132100D01*
X-1134300Y-457900D01*
X-1130100Y-458800D01*
X-1129500Y-459400D01*
X-1132600Y-459000D01*
G01X-1133300Y-461900D02*
Y-461420D01*
X-1133640Y-460240D01*
X-1134300Y-459200D01*
X-1135200Y-458900D01*
X-1136580D01*
X-1138060Y-459820D01*
X-1139360Y-461000D01*
X-1140240Y-462220D01*
X-1140880Y-463920D01*
X-1141300Y-465380D01*
X-1141500Y-467060D01*
Y-468020D01*
X-1141020Y-469220D01*
X-1139780Y-470700D01*
X-1137160D01*
X-1135840Y-469500D01*
X-1134980Y-468200D01*
X-1134940Y-468100D01*
X-1128180D01*
X-1128240Y-468240D01*
X-1128840Y-469340D01*
X-1129020Y-469800D01*
X-1129740Y-470700D01*
X-1130500Y-471460D01*
X-1131660Y-472420D01*
X-1132820Y-473200D01*
X-1133740Y-473740D01*
X-1136380Y-474500D01*
X-1141640D01*
X-1142540Y-474320D01*
X-1144220Y-473760D01*
X-1144900Y-473240D01*
X-1146240Y-471900D01*
X-1146780Y-471180D01*
X-1146940Y-470880D01*
X-1147320Y-469660D01*
X-1147500Y-468640D01*
Y-464780D01*
X-1146940Y-462540D01*
X-1146380Y-461580D01*
X-1145980Y-460780D01*
X-1145420Y-459880D01*
X-1143700Y-458140D01*
X-1142740Y-457380D01*
X-1142000Y-456820D01*
X-1140240Y-456040D01*
X-1139500Y-455660D01*
X-1138800Y-455480D01*
X-1137260Y-455300D01*
X-1134320D01*
X-1132020Y-455500D01*
X-1130940Y-455860D01*
X-1130580Y-456020D01*
X-1129260Y-456780D01*
X-1128940Y-457100D01*
X-1127820Y-458420D01*
X-1127060Y-460300D01*
X-1126900Y-460800D01*
Y-461900D01*
X-1133300D01*
G01X-1137900Y-458000D02*
X-1140300Y-459100D01*
X-1142500Y-460900D01*
X-1143900Y-462600D01*
X-1144800Y-467600D01*
X-1144200Y-470000D01*
X-1141000Y-472300D01*
X-1136400Y-472200D01*
X-1131600Y-469600D01*
X-1135400Y-470400D01*
X-1141100Y-471400D01*
X-1142100Y-470700D01*
X-1142700Y-469000D01*
X-1143100Y-467100D01*
X-1142700Y-464100D01*
X-1140500Y-459900D01*
X-1143400Y-463700D01*
X-1143600Y-465700D01*
X-1143900Y-467700D01*
X-1143000Y-469900D01*
G01X-1113500Y-459200D02*
X-1123500Y-459300D01*
X-1123700Y-460100D01*
X-1114300Y-460000D01*
X-1116500Y-460800D01*
X-1124200Y-461000D01*
X-1124400Y-461900D01*
X-1117600Y-461800D01*
X-1118800Y-462800D01*
X-1124500Y-462700D01*
X-1124600Y-463600D01*
X-1119300Y-463700D01*
X-1120100Y-464800D01*
X-1125000Y-464600D01*
Y-465500D01*
X-1120600Y-465700D01*
X-1120800Y-466700D01*
X-1125300Y-466500D01*
X-1125500Y-467400D01*
X-1121000Y-467600D01*
X-1121200Y-468700D01*
X-1125600Y-468400D01*
X-1125900Y-469100D01*
X-1121500Y-469500D01*
X-1121700Y-470700D01*
X-1126100Y-470000D01*
X-1126200Y-470700D01*
X-1121900Y-471200D01*
X-1122100Y-472000D01*
X-1126300Y-471700D01*
X-1126700Y-472300D01*
X-1122100Y-472700D01*
X-1122200Y-473100D01*
X-1126800Y-473200D01*
G01X-1114060Y-460760D02*
X-1114840Y-460920D01*
X-1115740Y-461140D01*
X-1116880Y-461820D01*
X-1117700Y-462640D01*
X-1118620Y-463340D01*
X-1118840Y-464020D01*
X-1119440Y-464820D01*
X-1119660Y-465480D01*
X-1120060Y-466280D01*
X-1120280Y-466960D01*
X-1120480Y-468360D01*
X-1120680Y-468940D01*
X-1120880Y-469940D01*
X-1121080Y-470540D01*
X-1121700Y-472980D01*
X-1121820Y-473900D01*
X-1127640D01*
X-1126920Y-471060D01*
X-1126720Y-470440D01*
X-1126500Y-468800D01*
X-1126320Y-467860D01*
X-1126120Y-467260D01*
X-1125920Y-466260D01*
X-1125720Y-465660D01*
X-1125300Y-464000D01*
X-1125120Y-462220D01*
X-1124920Y-461660D01*
X-1124720Y-460660D01*
X-1124520Y-460060D01*
X-1123720Y-456800D01*
X-1123580Y-455700D01*
X-1117880D01*
X-1118100Y-456160D01*
Y-458740D01*
X-1116500Y-457160D01*
X-1115780Y-456620D01*
X-1114680Y-456060D01*
X-1113560Y-455680D01*
X-1112460Y-455500D01*
X-1111720D01*
X-1112460Y-458440D01*
X-1114060Y-460760D01*
G01X-1123100Y-456500D02*
X-1118900Y-456600D01*
X-1118800Y-457600D01*
X-1123100Y-457500D01*
X-1123300Y-458500D01*
X-1113100Y-458400D01*
X-1112600Y-456400D01*
X-1116100Y-457600D01*
X-1113500D01*
G01X-1105100Y-471100D02*
X-1104060D01*
X-1103780Y-470820D01*
X-1103200Y-470640D01*
X-1102080Y-469740D01*
X-1100800Y-468240D01*
X-1100380Y-467400D01*
X-1100180Y-467100D01*
X-1099960Y-466660D01*
X-1099540Y-465720D01*
X-1099320Y-465060D01*
X-1099100Y-464180D01*
Y-461220D01*
X-1099360Y-460200D01*
X-1099660Y-459900D01*
X-1100700Y-458640D01*
X-1101220Y-458300D01*
X-1103340D01*
X-1103700Y-458640D01*
X-1105300Y-459840D01*
X-1105760Y-460320D01*
X-1106180Y-460940D01*
X-1107060Y-462020D01*
X-1107260Y-462880D01*
X-1107660Y-463660D01*
X-1108100Y-465000D01*
Y-468640D01*
X-1107620Y-469600D01*
X-1107140Y-470340D01*
X-1105980Y-471100D01*
X-1105100D01*
G01X-1112540Y-460460D02*
X-1110680Y-458140D01*
X-1109940Y-457580D01*
X-1109000Y-456840D01*
X-1108480Y-456660D01*
X-1107940Y-456400D01*
X-1107740Y-456200D01*
X-1107480Y-456060D01*
X-1106880Y-455860D01*
X-1106480Y-455660D01*
X-1105960Y-455480D01*
X-1104600Y-455300D01*
X-1103440Y-455100D01*
X-1100940D01*
X-1098240Y-455480D01*
X-1097720Y-455660D01*
X-1097020Y-456020D01*
X-1096180Y-456640D01*
X-1095620Y-456820D01*
X-1095540Y-456900D01*
X-1094200Y-458440D01*
X-1093660Y-459520D01*
X-1093460Y-460100D01*
X-1093100Y-461020D01*
Y-464400D01*
X-1093420Y-465360D01*
X-1094300Y-465520D01*
X-1094720Y-465740D01*
X-1095320Y-465940D01*
X-1096120Y-466340D01*
X-1096720Y-466540D01*
X-1097100Y-466720D01*
X-1098100Y-466920D01*
X-1098520Y-467140D01*
X-1099160Y-467360D01*
X-1101180Y-468700D01*
X-1094660D01*
X-1095220Y-469800D01*
X-1095560Y-470320D01*
X-1097480Y-472220D01*
X-1099940Y-473740D01*
X-1102580Y-474500D01*
X-1108800D01*
X-1109300Y-474340D01*
X-1111220Y-473560D01*
X-1111720Y-473240D01*
X-1113240Y-471720D01*
X-1113560Y-471240D01*
X-1113760Y-470660D01*
X-1114140Y-469980D01*
X-1114320Y-469120D01*
X-1114500Y-468680D01*
Y-464980D01*
X-1114320Y-464260D01*
X-1114140Y-463720D01*
X-1113940Y-463320D01*
X-1113720Y-462660D01*
X-1113560Y-462000D01*
X-1111880Y-460320D01*
X-1112540Y-460460D01*
G01X-1099300Y-466400D02*
X-1093800Y-464400D01*
X-1093900Y-461100D01*
X-1094800Y-459000D01*
X-1096800Y-457300D01*
X-1100000Y-456100D01*
X-1102800Y-455900D01*
X-1106300Y-456300D01*
X-1109600Y-458100D01*
X-1111400Y-460500D01*
X-1112900Y-462600D01*
X-1113600Y-465600D01*
X-1113500Y-469100D01*
X-1112100Y-471900D01*
X-1109600Y-473300D01*
X-1105700Y-473800D01*
X-1101000Y-473400D01*
X-1098200Y-471800D01*
X-1096600Y-470100D01*
X-1096000Y-469500D01*
X-1100800Y-469700D01*
X-1102300Y-471100D01*
X-1097900Y-470400D01*
X-1100300Y-471800D01*
X-1103200Y-471400D01*
X-1100600Y-472600D01*
X-1103000D01*
X-1103700Y-471900D01*
X-1103400Y-473000D01*
X-1104600Y-471900D01*
X-1106200D01*
X-1104100Y-473100D01*
X-1107200Y-472700D01*
X-1110100Y-472100D01*
X-1111500Y-470900D01*
X-1112600Y-468600D01*
X-1112700Y-466000D01*
X-1112400Y-463700D01*
X-1111400Y-461600D01*
X-1109600Y-459500D01*
X-1108100Y-458200D01*
X-1105900Y-457200D01*
X-1102200Y-456700D01*
X-1099600Y-457300D01*
X-1097000Y-458400D01*
X-1095500Y-459500D01*
X-1094600Y-461900D01*
X-1094500Y-463900D01*
X-1098800Y-465200D01*
X-1098600Y-464000D01*
X-1095100Y-463100D01*
X-1095300Y-462000D01*
X-1098500Y-463000D01*
X-1098600Y-461700D01*
X-1095600Y-461300D01*
X-1095900Y-460200D01*
X-1098400Y-460700D01*
X-1098900Y-459900D01*
X-1096600Y-459400D01*
X-1097100Y-458900D01*
X-1099400Y-459000D01*
X-1098800Y-458500D01*
X-1100600Y-458000D01*
X-1102400Y-457400D01*
X-1104200Y-457500D01*
X-1106200Y-458100D01*
X-1107900Y-459000D01*
X-1110500Y-462200D01*
X-1111800Y-464800D01*
Y-467700D01*
X-1110700Y-470300D01*
X-1108700Y-472000D01*
X-1106600Y-471900D01*
X-1107900Y-470300D01*
X-1108900Y-468700D01*
Y-465500D01*
X-1107900Y-462300D01*
X-1106500Y-459900D01*
X-1104100Y-458200D01*
X-1108000Y-460000D01*
X-1108100Y-461500D01*
X-1108700Y-461200D01*
X-1110300Y-463600D01*
X-1111000Y-466000D01*
X-1110700Y-468100D01*
X-1109500Y-470600D01*
X-1107700Y-471400D01*
X-1109300Y-469100D01*
X-1109800Y-467600D01*
X-1108600Y-462200D01*
X-1110400Y-466800D01*
G01X-1113600Y-460900D02*
X-1112100Y-459000D01*
G01X-1093100Y-469400D02*
X-1087900Y-469700D01*
X-1086500Y-471400D01*
X-1083400Y-472300D01*
X-1081000Y-472000D01*
X-1079300Y-470600D01*
X-1079000Y-468900D01*
X-1079500Y-467700D01*
X-1080300Y-466600D01*
X-1081800Y-466000D01*
X-1083300Y-465500D01*
X-1085300Y-465000D01*
X-1087900Y-464000D01*
X-1089100Y-463200D01*
X-1089800Y-461000D01*
X-1089500Y-459000D01*
X-1088600Y-457700D01*
X-1086500Y-456700D01*
X-1084600Y-456100D01*
X-1081900Y-455900D01*
X-1079900Y-455800D01*
X-1076900Y-456300D01*
X-1075000Y-457000D01*
X-1073700Y-458000D01*
X-1073300Y-459400D01*
X-1077600Y-459500D01*
X-1078100Y-458800D01*
X-1074300Y-458500D01*
X-1074600Y-457800D01*
X-1078200Y-458200D01*
X-1076000Y-457400D01*
X-1079100Y-457700D01*
X-1077100Y-456900D01*
X-1080100Y-457300D01*
X-1079200Y-456600D01*
X-1083100Y-456800D01*
X-1080600Y-457300D01*
X-1083400Y-457700D01*
X-1083600Y-457000D01*
X-1087900Y-458400D01*
X-1084000Y-458100D01*
X-1088600Y-459100D01*
X-1088800Y-461500D01*
X-1087700Y-463600D01*
X-1084400Y-464300D01*
X-1081200Y-465400D01*
X-1078800Y-467300D01*
X-1078300Y-470500D01*
X-1079900Y-472600D01*
X-1083500Y-473300D01*
X-1085600Y-472600D01*
X-1088800Y-470500D01*
X-1092600Y-470200D01*
X-1092100Y-471800D01*
X-1091700Y-471300D01*
X-1089300Y-471500D01*
X-1091300Y-472300D01*
X-1088700Y-471600D01*
X-1084000Y-473500D01*
X-1089100D01*
X-1091000Y-472900D01*
X-1087200Y-472800D01*
X-1082700Y-473700D01*
X-1079000Y-473600D01*
X-1076500Y-472300D01*
X-1074700Y-470600D01*
X-1074300Y-467300D01*
X-1074800Y-465300D01*
X-1078800Y-463600D01*
X-1081600Y-462900D01*
X-1083400Y-462500D01*
X-1084800Y-461500D01*
X-1085000Y-458900D01*
X-1088100Y-459800D01*
X-1087200Y-462700D01*
X-1085000Y-463400D01*
X-1082000Y-464100D01*
X-1079600Y-465100D01*
X-1078200Y-466500D01*
X-1077700Y-468500D01*
X-1077500Y-470100D01*
X-1079200Y-472800D01*
X-1076800Y-471400D01*
X-1075300Y-470000D01*
X-1077300Y-470900D01*
X-1075000Y-468800D01*
X-1075200Y-466100D01*
X-1082700Y-462700D01*
X-1084200Y-462900D01*
X-1086600Y-461800D01*
X-1087200Y-460300D01*
X-1085800Y-459800D01*
X-1086600Y-461000D01*
X-1085300Y-460400D01*
X-1085600Y-461400D01*
X-1076700Y-466500D01*
X-1075900Y-467100D01*
X-1075700Y-468400D01*
X-1076800Y-469500D01*
X-1077800Y-466200D01*
X-1075900Y-468800D01*
G01X-1093780Y-468700D02*
X-1087100D01*
Y-469740D01*
X-1086800Y-470060D01*
X-1086520Y-470600D01*
X-1085820Y-470820D01*
X-1085660Y-471000D01*
X-1085120Y-471260D01*
X-1084400Y-471500D01*
X-1082360D01*
X-1080540Y-470600D01*
X-1080100Y-470140D01*
Y-469780D01*
X-1079840Y-469380D01*
X-1080380Y-467740D01*
X-1081440Y-466940D01*
X-1082560Y-466720D01*
X-1085740Y-465920D01*
X-1086940Y-465520D01*
X-1087600Y-465360D01*
X-1087740Y-465200D01*
X-1088540Y-464800D01*
X-1089140Y-464200D01*
X-1089540Y-464000D01*
X-1089800Y-463740D01*
X-1090000Y-463340D01*
X-1090180Y-463180D01*
X-1090500Y-462200D01*
Y-459800D01*
X-1090320Y-459260D01*
X-1090140Y-458500D01*
X-1090000Y-458260D01*
X-1089000Y-457260D01*
X-1088860Y-456940D01*
X-1085920Y-455480D01*
X-1083620Y-455100D01*
X-1082060Y-454900D01*
X-1080520D01*
X-1078580Y-455100D01*
X-1076240Y-455480D01*
X-1075120Y-455860D01*
X-1074800Y-456020D01*
X-1073680Y-456760D01*
X-1073160Y-457300D01*
X-1072620Y-458020D01*
X-1072500Y-458240D01*
Y-460300D01*
X-1078500D01*
Y-459200D01*
X-1079580Y-458380D01*
X-1080160Y-458100D01*
X-1082380D01*
X-1083280Y-458360D01*
X-1084020Y-458940D01*
X-1084340Y-459900D01*
X-1084060Y-460720D01*
X-1083740Y-461340D01*
X-1081860Y-462280D01*
X-1079400Y-462500D01*
X-1078660Y-462680D01*
X-1078100Y-462860D01*
X-1076500Y-463460D01*
X-1075320Y-463860D01*
X-1075060Y-464000D01*
X-1073820Y-465220D01*
X-1073480Y-466260D01*
X-1073300Y-467160D01*
Y-468420D01*
X-1073860Y-470700D01*
X-1074000Y-470960D01*
X-1075140Y-472300D01*
X-1075280Y-472440D01*
X-1076600Y-473380D01*
X-1077320Y-473740D01*
X-1079600Y-474500D01*
X-1088240D01*
X-1089160Y-474320D01*
X-1089920Y-474120D01*
X-1090860Y-473760D01*
X-1091560Y-473400D01*
X-1092700Y-472460D01*
X-1093180Y-471980D01*
X-1093340Y-471480D01*
X-1093520Y-471100D01*
X-1093700Y-470320D01*
X-1093780Y-468700D01*
G01X-1095100D02*
X-1092800D01*
G01X-1058300Y-469400D02*
X-1055400Y-467100D01*
X-1053900Y-463700D01*
X-1054400Y-461200D01*
X-1055900Y-459900D01*
X-1054800Y-463500D01*
X-1055400Y-463600D01*
X-1054600Y-464500D01*
X-1055700D01*
X-1055400Y-465300D01*
X-1056200Y-466800D01*
G01X-1059300Y-457700D02*
X-1059100Y-455600D01*
X-1055200Y-456300D01*
X-1052700Y-457900D01*
X-1051100Y-460800D01*
X-1050900Y-465200D01*
X-1052900Y-469400D01*
X-1055300Y-471900D01*
X-1059000Y-473500D01*
X-1066000D01*
X-1068000Y-471900D01*
X-1070200Y-468700D01*
X-1070600Y-464500D01*
X-1069000Y-460500D01*
X-1066000Y-457500D01*
X-1063000Y-456500D01*
X-1059200Y-456000D01*
X-1053000Y-458500D01*
X-1052000Y-461500D01*
Y-465700D01*
X-1053400Y-468600D01*
X-1055700Y-471000D01*
X-1058900Y-472600D01*
X-1063700Y-473000D01*
X-1065900Y-473600D01*
X-1068300Y-472900D01*
X-1070600Y-469300D01*
X-1065100Y-472600D01*
X-1060800Y-472200D01*
X-1057200Y-470700D01*
X-1055200Y-469100D01*
X-1053300Y-466500D01*
X-1052500Y-463400D01*
X-1052900Y-460100D01*
X-1057000Y-457400D01*
X-1058700Y-457200D01*
X-1057000Y-458500D01*
X-1055100Y-459800D01*
X-1053800Y-460900D01*
X-1053400Y-463100D01*
X-1053600Y-465600D01*
X-1054800Y-467500D01*
X-1056400Y-469200D01*
X-1058500Y-470200D01*
X-1060200Y-470700D01*
X-1061500Y-471400D01*
X-1063300Y-471600D01*
X-1065400Y-471500D01*
X-1069000Y-469300D01*
X-1069600Y-466400D01*
X-1069700Y-463700D01*
X-1068600Y-461200D01*
X-1066700Y-459200D01*
X-1063900Y-457600D01*
X-1061100Y-457000D01*
X-1059600D01*
X-1060200Y-457500D01*
X-1063300Y-458000D01*
X-1065300Y-459500D01*
X-1066900Y-460600D01*
X-1067900Y-462100D01*
X-1068800Y-464300D01*
X-1068700Y-466900D01*
X-1068200Y-469100D01*
X-1066900Y-470200D01*
X-1064300Y-470900D01*
X-1065700Y-469300D01*
X-1065800Y-465900D01*
X-1065300Y-462900D01*
X-1061200Y-458200D01*
X-1063600Y-458900D01*
X-1066400Y-461300D01*
X-1067800Y-464200D01*
Y-467200D01*
X-1067400Y-469300D01*
X-1066300Y-469700D01*
X-1067100Y-466400D01*
X-1066600Y-463400D01*
X-1064700Y-460000D01*
X-1062600Y-458800D01*
X-1065300Y-461700D01*
X-1066700Y-467400D01*
G01X-1060840Y-455100D02*
X-1057160D01*
X-1055260Y-455480D01*
X-1054740Y-455640D01*
X-1053380Y-456420D01*
X-1052660Y-456800D01*
X-1052020Y-457420D01*
X-1051820Y-458020D01*
X-1051200Y-458660D01*
X-1051000Y-459060D01*
X-1050840Y-459200D01*
X-1050700Y-459780D01*
Y-460140D01*
X-1050400Y-460460D01*
X-1050280Y-460680D01*
X-1050100Y-461740D01*
Y-464240D01*
X-1050280Y-465160D01*
X-1050480Y-465980D01*
X-1050680Y-467120D01*
X-1051220Y-468180D01*
X-1051840Y-469020D01*
X-1052040Y-469600D01*
X-1052740Y-470500D01*
X-1054480Y-472240D01*
X-1055000Y-472580D01*
X-1055420Y-472780D01*
X-1056220Y-473380D01*
X-1056920Y-473740D01*
X-1059380Y-474500D01*
X-1065600D01*
X-1067860Y-473740D01*
X-1068160Y-473600D01*
X-1069500Y-472460D01*
X-1069820Y-472120D01*
X-1070380Y-471200D01*
X-1071140Y-469860D01*
X-1071300Y-469400D01*
Y-464580D01*
X-1071120Y-463880D01*
X-1070740Y-462900D01*
X-1070540Y-462320D01*
X-1069980Y-461000D01*
X-1068840Y-459500D01*
X-1066900Y-457560D01*
X-1066180Y-457020D01*
X-1065400Y-456620D01*
X-1064440Y-456040D01*
X-1063500Y-455660D01*
X-1062940Y-455480D01*
X-1060840Y-455100D01*
G01X-1057800Y-458580D02*
X-1057000Y-459120D01*
X-1056760Y-459840D01*
X-1056340Y-460460D01*
X-1056100Y-461640D01*
Y-463760D01*
X-1056320Y-464860D01*
X-1056720Y-466060D01*
X-1056940Y-466920D01*
X-1057200Y-467460D01*
X-1057640Y-467880D01*
X-1058040Y-468480D01*
X-1059960Y-470420D01*
X-1061020Y-470840D01*
X-1061420Y-471100D01*
X-1062720D01*
X-1063340Y-470840D01*
X-1063860Y-470600D01*
X-1064360Y-470080D01*
X-1064820Y-469400D01*
X-1065100Y-468840D01*
Y-464920D01*
X-1064880Y-464120D01*
X-1064420Y-462780D01*
X-1064160Y-462520D01*
X-1063620Y-461700D01*
X-1063200Y-460840D01*
X-1062500Y-460140D01*
X-1062120Y-459860D01*
X-1061720Y-459360D01*
X-1060600Y-458580D01*
X-1060040Y-458300D01*
X-1058360D01*
X-1057800Y-458580D01*
G01X-1040300Y-459100D02*
X-1041400Y-464800D01*
G01X-1044800Y-458200D02*
X-1041400D01*
X-1044300Y-472700D01*
X-1047400Y-472300D01*
X-1044100Y-458800D01*
X-1042400Y-459100D01*
X-1045100Y-471900D01*
X-1046500D01*
X-1043400Y-459700D01*
X-1045600Y-471500D01*
G01X-1036600Y-449900D02*
X-1036800Y-451300D01*
X-1038600Y-452400D01*
X-1039800Y-456100D01*
X-1033700Y-456500D01*
X-1032300Y-452100D01*
X-1028400Y-452000D01*
X-1028900Y-455400D01*
X-1027200Y-456600D01*
X-1025900Y-456800D01*
X-1026200Y-458200D01*
X-1030000Y-458400D01*
X-1031800Y-468900D01*
X-1030400Y-471700D01*
X-1029400D01*
X-1029600Y-473300D01*
X-1033100Y-473400D01*
X-1036100Y-472800D01*
X-1036200Y-470500D01*
X-1035900Y-467100D01*
X-1034400Y-461400D01*
X-1033800Y-458800D01*
X-1033500Y-458400D01*
X-1035000Y-458200D01*
X-1039600D01*
X-1040800Y-458300D01*
X-1043600Y-473200D01*
X-1048000Y-473000D01*
X-1045100Y-459400D01*
X-1044900Y-458400D01*
X-1048700D01*
X-1048100Y-456600D01*
X-1044900Y-456400D01*
X-1045200Y-457700D01*
X-1047600Y-457500D01*
X-1026500D01*
G01X-1049580Y-459100D02*
X-1048740Y-455700D01*
X-1044900D01*
Y-454780D01*
X-1044720Y-454060D01*
X-1044340Y-452920D01*
X-1043940Y-452120D01*
X-1043740Y-451520D01*
X-1043600Y-451260D01*
X-1042340Y-450000D01*
X-1042080Y-449860D01*
X-1040580Y-449480D01*
X-1039440Y-449300D01*
X-1036140D01*
X-1035440Y-449400D01*
X-1035480Y-449540D01*
X-1035680Y-450360D01*
X-1035880Y-451280D01*
X-1036000Y-451900D01*
X-1036740D01*
X-1037060Y-452200D01*
X-1037860Y-452600D01*
X-1038220Y-452980D01*
X-1038480Y-453740D01*
X-1038960Y-455700D01*
X-1034020D01*
X-1033720Y-455080D01*
X-1033500Y-453400D01*
X-1032940Y-451100D01*
X-1027260D01*
X-1027280Y-451180D01*
X-1027480Y-452780D01*
X-1027860Y-454280D01*
X-1028100Y-454760D01*
Y-455700D01*
X-1024800D01*
X-1024880Y-455940D01*
X-1025080Y-456940D01*
X-1025280Y-457540D01*
X-1025480Y-458560D01*
X-1025620Y-459100D01*
X-1029100D01*
Y-460000D01*
X-1029280Y-460540D01*
X-1029480Y-461540D01*
X-1029680Y-462140D01*
X-1029880Y-462960D01*
X-1030100Y-464000D01*
X-1030280Y-465560D01*
X-1030480Y-466140D01*
X-1030680Y-467140D01*
X-1030880Y-467740D01*
X-1031040Y-468400D01*
X-1031300Y-468660D01*
Y-469800D01*
X-1030300Y-470560D01*
X-1029940Y-470900D01*
X-1028220D01*
X-1028680Y-472780D01*
X-1028880Y-474120D01*
Y-474140D01*
X-1030720Y-474300D01*
X-1032860D01*
X-1034380Y-474120D01*
X-1035860Y-473740D01*
X-1036640Y-473280D01*
X-1036960Y-472660D01*
X-1037100Y-472280D01*
Y-470160D01*
X-1036920Y-469260D01*
X-1036700Y-468640D01*
X-1036500Y-466840D01*
X-1036320Y-466260D01*
X-1036120Y-465260D01*
X-1035920Y-464660D01*
X-1035720Y-463660D01*
X-1035520Y-463060D01*
X-1035320Y-462060D01*
X-1035120Y-461440D01*
X-1034820Y-459100D01*
X-1039900D01*
Y-460220D01*
X-1040280Y-461780D01*
X-1040480Y-463380D01*
X-1041280Y-466540D01*
X-1041480Y-467140D01*
X-1041700Y-468200D01*
X-1041880Y-469760D01*
X-1042080Y-470340D01*
X-1042280Y-471360D01*
X-1042480Y-472140D01*
X-1042680Y-472740D01*
X-1042880Y-473740D01*
X-1042940Y-473900D01*
X-1049140D01*
X-1048300Y-470620D01*
X-1048100Y-469020D01*
X-1047920Y-468260D01*
X-1047720Y-467660D01*
X-1047520Y-466660D01*
X-1047320Y-466060D01*
X-1047120Y-465060D01*
X-1046920Y-464460D01*
X-1046700Y-463400D01*
X-1046500Y-462020D01*
X-1046140Y-460500D01*
X-1045900Y-460040D01*
Y-459100D01*
X-1049580D01*
G01X-1038400Y-451100D02*
X-1040600Y-455800D01*
X-1043300D01*
X-1041400Y-451300D01*
X-1038900Y-451000D01*
X-1041200Y-455000D01*
X-1042000Y-455100D01*
X-1040500Y-452000D01*
G01X-1037500Y-449800D02*
X-1037800Y-451000D01*
X-1038500Y-450100D01*
X-1042000Y-450700D01*
X-1043100Y-452300D01*
X-1044100Y-455100D01*
X-1044200Y-456600D01*
X-1036600Y-456800D01*
G01X-1031100Y-472500D02*
X-1031400Y-470900D01*
X-1031900Y-472200D01*
X-1035200D01*
Y-467600D01*
X-1032000Y-453700D01*
X-1030500Y-453800D01*
X-1030000Y-456700D01*
X-1033400Y-471900D01*
X-1034300Y-471600D01*
X-1034200Y-467100D01*
X-1031400Y-454500D01*
X-1030700Y-456500D01*
X-1033700Y-470600D01*
X-1032700Y-461100D01*
G01X-1032000Y-452900D02*
X-1029300D01*
X-1028000Y-457000D01*
X-1029500Y-453600D01*
X-1029100Y-457300D01*
X-1032800Y-472800D01*
X-1030200Y-472600D01*
G54D12*
G01X-1181990Y-545833D02*
X-1181410Y-545208D01*
X-1180975Y-544167D01*
X-1180685Y-542708D01*
X-1180975Y-541458D01*
X-1181555Y-540625D01*
X-1182570Y-540000D01*
X-1186485D01*
Y-552500D01*
X-1181700D01*
X-1180685Y-551667D01*
X-1180105Y-550417D01*
X-1179815Y-548958D01*
X-1180105Y-547500D01*
X-1180975Y-546250D01*
X-1181990Y-545833D01*
X-1186485D01*
G01X-1171350Y-552500D02*
X-1172510Y-552292D01*
X-1173525Y-551459D01*
X-1174395Y-550208D01*
X-1174975Y-548750D01*
X-1175265Y-547083D01*
Y-545417D01*
X-1174975Y-543750D01*
X-1174395Y-542292D01*
X-1173525Y-541042D01*
X-1172510Y-540208D01*
X-1171350Y-540000D01*
X-1170190Y-540208D01*
X-1169175Y-541042D01*
X-1168305Y-542292D01*
X-1167725Y-543750D01*
X-1167435Y-545417D01*
Y-547083D01*
X-1167725Y-548750D01*
X-1168305Y-550208D01*
X-1169175Y-551459D01*
X-1170190Y-552292D01*
X-1171350Y-552500D01*
G01X-1159550Y-540000D02*
Y-552500D01*
G01X-1162885Y-540000D02*
X-1156215D01*
G01X-1138995Y-550834D02*
X-1137835Y-551875D01*
X-1136530Y-552500D01*
X-1135370D01*
X-1134210Y-551875D01*
X-1133340Y-550834D01*
X-1132905Y-549375D01*
X-1133195Y-547917D01*
X-1133920Y-546667D01*
X-1135225Y-545833D01*
X-1136965Y-545417D01*
X-1137980Y-544584D01*
X-1138415Y-543125D01*
X-1138125Y-541667D01*
X-1137400Y-540625D01*
X-1136385Y-540000D01*
X-1135370D01*
X-1134355Y-540417D01*
X-1133485Y-541458D01*
G01X-1125890Y-540000D02*
X-1122410D01*
G01X-1124150D02*
Y-552500D01*
G01X-1125890D02*
X-1122410D01*
G01X-1115540D02*
Y-540000D01*
X-1112640D01*
X-1111480Y-540625D01*
X-1110610Y-541458D01*
X-1109885Y-542708D01*
X-1109305Y-544167D01*
X-1109160Y-546250D01*
X-1109305Y-548333D01*
X-1109885Y-549792D01*
X-1110610Y-551042D01*
X-1111480Y-551875D01*
X-1112640Y-552500D01*
X-1115540D01*
G01X-1097650D02*
X-1103450D01*
Y-540000D01*
X-1097650D01*
G01X-1099970Y-546042D02*
X-1103450D01*
G01X-1079995Y-550834D02*
X-1078835Y-551875D01*
X-1077530Y-552500D01*
X-1076370D01*
X-1075210Y-551875D01*
X-1074340Y-550834D01*
X-1073905Y-549375D01*
X-1074195Y-547917D01*
X-1074920Y-546667D01*
X-1076225Y-545833D01*
X-1077965Y-545417D01*
X-1078980Y-544584D01*
X-1079415Y-543125D01*
X-1079125Y-541667D01*
X-1078400Y-540625D01*
X-1077385Y-540000D01*
X-1076370D01*
X-1075355Y-540417D01*
X-1074485Y-541458D01*
G01X-1066890Y-540000D02*
X-1063410D01*
G01X-1065150D02*
Y-552500D01*
G01X-1066890D02*
X-1063410D01*
G01X-1056250Y-540000D02*
Y-552500D01*
X-1050450D01*
G01X-1044740D02*
Y-540000D01*
G01X-1039230D02*
X-1044740Y-547709D01*
G01X-1038360Y-552500D02*
X-1042275Y-544167D01*
G01X-1032795Y-550834D02*
X-1031635Y-551875D01*
X-1030330Y-552500D01*
X-1029170D01*
X-1028010Y-551875D01*
X-1027140Y-550834D01*
X-1026705Y-549375D01*
X-1026995Y-547917D01*
X-1027720Y-546667D01*
X-1029025Y-545833D01*
X-1030765Y-545417D01*
X-1031780Y-544584D01*
X-1032215Y-543125D01*
X-1031925Y-541667D01*
X-1031200Y-540625D01*
X-1030185Y-540000D01*
X-1029170D01*
X-1028155Y-540417D01*
X-1027285Y-541458D01*
G01X-1014760Y-541042D02*
X-1015630Y-540417D01*
X-1016645Y-540000D01*
X-1017805D01*
X-1019110Y-540625D01*
X-1020125Y-541667D01*
X-1020850Y-542917D01*
X-1021430Y-545000D01*
X-1021575Y-546875D01*
X-1021285Y-548750D01*
X-1020850Y-550000D01*
X-1019980Y-551250D01*
X-1018965Y-552083D01*
X-1017950Y-552500D01*
X-1016935D01*
X-1015920Y-552083D01*
X-1015050Y-551459D01*
X-1014325Y-550625D01*
G01X-1009050Y-552500D02*
Y-540000D01*
X-1005425D01*
X-1004265Y-540625D01*
X-1003540Y-541458D01*
X-1003250Y-543125D01*
X-1003540Y-544792D01*
X-1004410Y-545833D01*
X-1005425Y-546458D01*
X-1009050D01*
G01X-1005425D02*
X-1003250Y-552500D01*
G01X-991450D02*
X-997250D01*
Y-540000D01*
X-991450D01*
G01X-993770Y-546042D02*
X-997250D01*
G01X-979650Y-552500D02*
X-985450D01*
Y-540000D01*
X-979650D01*
G01X-981970Y-546042D02*
X-985450D01*
G01X-974085Y-552500D02*
Y-540000D01*
X-967415Y-552500D01*
Y-540000D01*
G54D13*
G01X-1654068Y-120950D02*
X-1655168Y-122050D01*
G01X-1655368Y-121500D02*
X-1653868D01*
G01X-1654068Y-122050D02*
X-1655168Y-120950D01*
G01X-1654618Y-120750D02*
Y-122250D01*
G01X-1185925Y-592500D02*
X-1178575Y-577500D01*
G01X-1185925D02*
X-1178575Y-592500D01*
G01X-1168050D02*
X-1166825Y-592250D01*
X-1165425Y-591500D01*
X-1164550Y-590250D01*
X-1164200Y-588500D01*
X-1164550Y-586750D01*
X-1165600Y-585250D01*
X-1167175Y-584500D01*
X-1168925D01*
X-1169975Y-584000D01*
X-1170850Y-582750D01*
X-1171200Y-581000D01*
X-1170675Y-579250D01*
X-1169450Y-578000D01*
X-1168050Y-577500D01*
X-1166650Y-578000D01*
X-1165425Y-579250D01*
X-1164900Y-581000D01*
X-1165250Y-582750D01*
X-1166125Y-584000D01*
X-1167175Y-584500D01*
X-1168925D01*
X-1170500Y-585250D01*
X-1171550Y-586750D01*
X-1171900Y-588500D01*
X-1171550Y-590250D01*
X-1170675Y-591500D01*
X-1169275Y-592250D01*
X-1168050Y-592500D01*
G01X-1153850D02*
X-1152625Y-592250D01*
X-1151225Y-591500D01*
X-1150350Y-590250D01*
X-1150000Y-588500D01*
X-1150350Y-586750D01*
X-1151400Y-585250D01*
X-1152975Y-584500D01*
X-1154725D01*
X-1155775Y-584000D01*
X-1156650Y-582750D01*
X-1157000Y-581000D01*
X-1156475Y-579250D01*
X-1155250Y-578000D01*
X-1153850Y-577500D01*
X-1152450Y-578000D01*
X-1151225Y-579250D01*
X-1150700Y-581000D01*
X-1151050Y-582750D01*
X-1151925Y-584000D01*
X-1152975Y-584500D01*
X-1154725D01*
X-1156300Y-585250D01*
X-1157350Y-586750D01*
X-1157700Y-588500D01*
X-1157350Y-590250D01*
X-1156475Y-591500D01*
X-1155075Y-592250D01*
X-1153850Y-592500D01*
G01X-1140000D02*
X-1139650Y-589250D01*
X-1139125Y-586500D01*
X-1138425Y-584000D01*
X-1137550Y-581250D01*
X-1136150Y-577500D01*
X-1143150D01*
G01X-1129300Y-590250D02*
X-1128250Y-591500D01*
X-1127025Y-592250D01*
X-1125450Y-592500D01*
X-1123875Y-592000D01*
X-1122650Y-591000D01*
X-1121775Y-589250D01*
X-1121600Y-587250D01*
X-1121950Y-585250D01*
X-1122825Y-584000D01*
X-1124050Y-583000D01*
X-1125275Y-582750D01*
X-1126500Y-583000D01*
X-1128075Y-584000D01*
X-1127550Y-577500D01*
X-1122825D01*
G01X-1111600Y-592500D02*
X-1111250Y-589250D01*
X-1110725Y-586500D01*
X-1110025Y-584000D01*
X-1109150Y-581250D01*
X-1107750Y-577500D01*
X-1114750D01*
G01X-1097050Y-592500D02*
Y-577500D01*
X-1099150Y-580500D01*
G01Y-592500D02*
X-1094950D01*
G01X-1085125Y-587500D02*
X-1080575D01*
G01X-1068650Y-577500D02*
X-1070050Y-578000D01*
X-1071100Y-579250D01*
X-1071800Y-580750D01*
X-1072325Y-582750D01*
X-1072500Y-585000D01*
X-1072325Y-587250D01*
X-1071800Y-589250D01*
X-1071100Y-590750D01*
X-1070050Y-592000D01*
X-1068650Y-592500D01*
X-1067250Y-592000D01*
X-1066200Y-590750D01*
X-1065500Y-589250D01*
X-1064975Y-587250D01*
X-1064800Y-585000D01*
X-1064975Y-582750D01*
X-1065500Y-580750D01*
X-1066200Y-579250D01*
X-1067250Y-578000D01*
X-1068650Y-577500D01*
G01X-1054450D02*
X-1055850Y-578000D01*
X-1056900Y-579250D01*
X-1057600Y-580750D01*
X-1058125Y-582750D01*
X-1058300Y-585000D01*
X-1058125Y-587250D01*
X-1057600Y-589250D01*
X-1056900Y-590750D01*
X-1055850Y-592000D01*
X-1054450Y-592500D01*
X-1053050Y-592000D01*
X-1052000Y-590750D01*
X-1051300Y-589250D01*
X-1050775Y-587250D01*
X-1050600Y-585000D01*
X-1050775Y-582750D01*
X-1051300Y-580750D01*
X-1052000Y-579250D01*
X-1053050Y-578000D01*
X-1054450Y-577500D01*
G01X-1044100Y-590250D02*
X-1043050Y-591500D01*
X-1041825Y-592250D01*
X-1040250Y-592500D01*
X-1038675Y-592000D01*
X-1037450Y-591000D01*
X-1036575Y-589250D01*
X-1036400Y-587250D01*
X-1036750Y-585250D01*
X-1037625Y-584000D01*
X-1038850Y-583000D01*
X-1040075Y-582750D01*
X-1041300Y-583000D01*
X-1042875Y-584000D01*
X-1042350Y-577500D01*
X-1037625D01*
G01X-911875Y-592500D02*
X-907500Y-577500D01*
X-903125Y-592500D01*
G01X-904700Y-587250D02*
X-910300D01*
G01X-798796Y-161300D02*
X-799896Y-162400D01*
G01X-800096Y-161850D02*
X-798596D01*
G01X-798796Y-162400D02*
X-799896Y-161300D01*
G01X-799346Y-161100D02*
Y-162600D01*
G01X-778262Y-82550D02*
X-777162Y-83650D01*
G01X-776962Y-83100D02*
X-778462D01*
G01X-778262Y-83650D02*
X-777162Y-82550D01*
G01X-777712Y-82350D02*
Y-83850D01*
G54D14*
G01X-1655692Y-98650D02*
Y-95650D01*
X-1654397Y-97800D01*
X-1656147D01*
G01X-1652315Y-14600D02*
X-1652595Y-14850D01*
X-1652910Y-15000D01*
X-1653190D01*
X-1653470Y-14850D01*
X-1653680Y-14600D01*
X-1653785Y-14250D01*
X-1653715Y-13900D01*
X-1653540Y-13600D01*
X-1653225Y-13400D01*
X-1652805Y-13300D01*
X-1652560Y-13100D01*
X-1652455Y-12750D01*
X-1652525Y-12400D01*
X-1652700Y-12150D01*
X-1652945Y-12000D01*
X-1653190D01*
X-1653435Y-12100D01*
X-1653645Y-12350D01*
G01X-1655780Y-15000D02*
X-1655850Y-14350D01*
X-1655955Y-13800D01*
X-1656095Y-13300D01*
X-1656270Y-12750D01*
X-1656550Y-12000D01*
X-1655150D01*
G01X-1628815Y-15600D02*
X-1629095Y-15850D01*
X-1629410Y-16000D01*
X-1629690D01*
X-1629970Y-15850D01*
X-1630180Y-15600D01*
X-1630285Y-15250D01*
X-1630215Y-14900D01*
X-1630040Y-14600D01*
X-1629725Y-14400D01*
X-1629305Y-14300D01*
X-1629060Y-14100D01*
X-1628955Y-13750D01*
X-1629025Y-13400D01*
X-1629200Y-13150D01*
X-1629445Y-13000D01*
X-1629690D01*
X-1629935Y-13100D01*
X-1630145Y-13350D01*
G01X-1632350Y-16000D02*
Y-13000D01*
X-1631930Y-13600D01*
G01Y-16000D02*
X-1632770D01*
G01X-1634485Y-13500D02*
X-1634695Y-13200D01*
X-1634940Y-13050D01*
X-1635220Y-13000D01*
X-1635570Y-13100D01*
X-1635815Y-13350D01*
X-1635885Y-13650D01*
X-1635850Y-13950D01*
X-1635710Y-14200D01*
X-1635010Y-14700D01*
X-1634695Y-15050D01*
X-1634485Y-15550D01*
X-1634415Y-16000D01*
X-1635885D01*
G01X-1591400Y-19000D02*
Y-16000D01*
X-1592240D01*
X-1592520Y-16150D01*
X-1592730Y-16500D01*
X-1592800Y-16900D01*
X-1592730Y-17300D01*
X-1592555Y-17600D01*
X-1592240Y-17750D01*
X-1591400D01*
G01X-1594900Y-19000D02*
Y-16000D01*
X-1594480Y-16600D01*
G01Y-19000D02*
X-1595320D01*
G01X-1597630D02*
X-1597700Y-18350D01*
X-1597805Y-17800D01*
X-1597945Y-17300D01*
X-1598120Y-16750D01*
X-1598400Y-16000D01*
X-1597000D01*
G01X-1600045Y-18000D02*
X-1600955D01*
G01X-1602600Y-19000D02*
Y-16000D01*
X-1603440D01*
X-1603720Y-16150D01*
X-1603930Y-16500D01*
X-1604000Y-16900D01*
X-1603930Y-17300D01*
X-1603755Y-17600D01*
X-1603440Y-17750D01*
X-1602600D01*
G01X-1605435Y-16500D02*
X-1605645Y-16200D01*
X-1605890Y-16050D01*
X-1606170Y-16000D01*
X-1606520Y-16100D01*
X-1606765Y-16350D01*
X-1606835Y-16650D01*
X-1606800Y-16950D01*
X-1606660Y-17200D01*
X-1605960Y-17700D01*
X-1605645Y-18050D01*
X-1605435Y-18550D01*
X-1605365Y-19000D01*
X-1606835D01*
G01X-1608900Y-16000D02*
X-1608620Y-16100D01*
X-1608410Y-16350D01*
X-1608270Y-16650D01*
X-1608165Y-17050D01*
X-1608130Y-17500D01*
X-1608165Y-17950D01*
X-1608270Y-18350D01*
X-1608410Y-18650D01*
X-1608620Y-18900D01*
X-1608900Y-19000D01*
X-1609180Y-18900D01*
X-1609390Y-18650D01*
X-1609530Y-18350D01*
X-1609635Y-17950D01*
X-1609670Y-17500D01*
X-1609635Y-17050D01*
X-1609530Y-16650D01*
X-1609390Y-16350D01*
X-1609180Y-16100D01*
X-1608900Y-16000D01*
G01X-1550400Y-18500D02*
Y-15500D01*
X-1551240D01*
X-1551520Y-15650D01*
X-1551730Y-16000D01*
X-1551800Y-16400D01*
X-1551730Y-16800D01*
X-1551555Y-17100D01*
X-1551240Y-17250D01*
X-1550400D01*
G01X-1553235Y-16000D02*
X-1553445Y-15700D01*
X-1553690Y-15550D01*
X-1553970Y-15500D01*
X-1554320Y-15600D01*
X-1554565Y-15850D01*
X-1554635Y-16150D01*
X-1554600Y-16450D01*
X-1554460Y-16700D01*
X-1553760Y-17200D01*
X-1553445Y-17550D01*
X-1553235Y-18050D01*
X-1553165Y-18500D01*
X-1554635D01*
G01X-1556700D02*
Y-15500D01*
X-1556280Y-16100D01*
G01Y-18500D02*
X-1557120D01*
G01X-1559045Y-17500D02*
X-1559955D01*
G01X-1561600Y-18500D02*
Y-15500D01*
X-1562440D01*
X-1562720Y-15650D01*
X-1562930Y-16000D01*
X-1563000Y-16400D01*
X-1562930Y-16800D01*
X-1562755Y-17100D01*
X-1562440Y-17250D01*
X-1561600D01*
G01X-1564435Y-16000D02*
X-1564645Y-15700D01*
X-1564890Y-15550D01*
X-1565170Y-15500D01*
X-1565520Y-15600D01*
X-1565765Y-15850D01*
X-1565835Y-16150D01*
X-1565800Y-16450D01*
X-1565660Y-16700D01*
X-1564960Y-17200D01*
X-1564645Y-17550D01*
X-1564435Y-18050D01*
X-1564365Y-18500D01*
X-1565835D01*
G01X-1568320D02*
Y-15500D01*
X-1567025Y-17650D01*
X-1568775D01*
G01X-1508770Y-16100D02*
Y-13100D01*
X-1509610D01*
X-1509890Y-13250D01*
X-1510100Y-13600D01*
X-1510170Y-14000D01*
X-1510100Y-14400D01*
X-1509925Y-14700D01*
X-1509610Y-14850D01*
X-1508770D01*
G01X-1511605Y-13600D02*
X-1511815Y-13300D01*
X-1512060Y-13150D01*
X-1512340Y-13100D01*
X-1512690Y-13200D01*
X-1512935Y-13450D01*
X-1513005Y-13750D01*
X-1512970Y-14050D01*
X-1512830Y-14300D01*
X-1512130Y-14800D01*
X-1511815Y-15150D01*
X-1511605Y-15650D01*
X-1511535Y-16100D01*
X-1513005D01*
G01X-1514300Y-15650D02*
X-1514510Y-15900D01*
X-1514755Y-16050D01*
X-1515070Y-16100D01*
X-1515385Y-16000D01*
X-1515630Y-15800D01*
X-1515805Y-15450D01*
X-1515840Y-15050D01*
X-1515770Y-14650D01*
X-1515595Y-14400D01*
X-1515350Y-14200D01*
X-1515105Y-14150D01*
X-1514860Y-14200D01*
X-1514545Y-14400D01*
X-1514650Y-13100D01*
X-1515595D01*
G01X-1517415Y-15100D02*
X-1518325D01*
G01X-1519970Y-16100D02*
Y-13100D01*
X-1520810D01*
X-1521090Y-13250D01*
X-1521300Y-13600D01*
X-1521370Y-14000D01*
X-1521300Y-14400D01*
X-1521125Y-14700D01*
X-1520810Y-14850D01*
X-1519970D01*
G01X-1522805Y-13600D02*
X-1523015Y-13300D01*
X-1523260Y-13150D01*
X-1523540Y-13100D01*
X-1523890Y-13200D01*
X-1524135Y-13450D01*
X-1524205Y-13750D01*
X-1524170Y-14050D01*
X-1524030Y-14300D01*
X-1523330Y-14800D01*
X-1523015Y-15150D01*
X-1522805Y-15650D01*
X-1522735Y-16100D01*
X-1524205D01*
G01X-1526270D02*
X-1526515Y-16050D01*
X-1526795Y-15900D01*
X-1526970Y-15650D01*
X-1527040Y-15300D01*
X-1526970Y-14950D01*
X-1526760Y-14650D01*
X-1526445Y-14500D01*
X-1526095D01*
X-1525885Y-14400D01*
X-1525710Y-14150D01*
X-1525640Y-13800D01*
X-1525745Y-13450D01*
X-1525990Y-13200D01*
X-1526270Y-13100D01*
X-1526550Y-13200D01*
X-1526795Y-13450D01*
X-1526900Y-13800D01*
X-1526830Y-14150D01*
X-1526655Y-14400D01*
X-1526445Y-14500D01*
X-1526095D01*
X-1525780Y-14650D01*
X-1525570Y-14950D01*
X-1525500Y-15300D01*
X-1525570Y-15650D01*
X-1525745Y-15900D01*
X-1526025Y-16050D01*
X-1526270Y-16100D01*
G01X-1470370Y-16280D02*
Y-13280D01*
X-1471210D01*
X-1471490Y-13430D01*
X-1471700Y-13780D01*
X-1471770Y-14180D01*
X-1471700Y-14580D01*
X-1471525Y-14880D01*
X-1471210Y-15030D01*
X-1470370D01*
G01X-1473205Y-13780D02*
X-1473415Y-13480D01*
X-1473660Y-13330D01*
X-1473940Y-13280D01*
X-1474290Y-13380D01*
X-1474535Y-13630D01*
X-1474605Y-13930D01*
X-1474570Y-14230D01*
X-1474430Y-14480D01*
X-1473730Y-14980D01*
X-1473415Y-15330D01*
X-1473205Y-15830D01*
X-1473135Y-16280D01*
X-1474605D01*
G01X-1476075Y-15930D02*
X-1476320Y-16180D01*
X-1476600Y-16280D01*
X-1476880Y-16180D01*
X-1477125Y-15880D01*
X-1477300Y-15430D01*
X-1477370Y-14980D01*
Y-14430D01*
X-1477300Y-13980D01*
X-1477125Y-13580D01*
X-1476915Y-13380D01*
X-1476670Y-13280D01*
X-1476390Y-13380D01*
X-1476180Y-13580D01*
X-1476040Y-13880D01*
X-1475970Y-14280D01*
X-1476040Y-14630D01*
X-1476215Y-14980D01*
X-1476425Y-15180D01*
X-1476670Y-15230D01*
X-1476950Y-15130D01*
X-1477160Y-14880D01*
X-1477370Y-14430D01*
G01X-1479015Y-15280D02*
X-1479925D01*
G01X-1481570Y-16280D02*
Y-13280D01*
X-1482410D01*
X-1482690Y-13430D01*
X-1482900Y-13780D01*
X-1482970Y-14180D01*
X-1482900Y-14580D01*
X-1482725Y-14880D01*
X-1482410Y-15030D01*
X-1481570D01*
G01X-1484300Y-15680D02*
X-1484510Y-16030D01*
X-1484790Y-16230D01*
X-1485105Y-16280D01*
X-1485385Y-16230D01*
X-1485665Y-15980D01*
X-1485840Y-15680D01*
X-1485875Y-15380D01*
X-1485805Y-15030D01*
X-1485560Y-14780D01*
X-1485315Y-14680D01*
X-1485000D01*
G01X-1485315D02*
X-1485525Y-14530D01*
X-1485700Y-14280D01*
X-1485770Y-13980D01*
X-1485700Y-13680D01*
X-1485525Y-13430D01*
X-1485210Y-13280D01*
X-1484895Y-13330D01*
X-1484580Y-13530D01*
G01X-1487205Y-13780D02*
X-1487415Y-13480D01*
X-1487660Y-13330D01*
X-1487940Y-13280D01*
X-1488290Y-13380D01*
X-1488535Y-13630D01*
X-1488605Y-13930D01*
X-1488570Y-14230D01*
X-1488430Y-14480D01*
X-1487730Y-14980D01*
X-1487415Y-15330D01*
X-1487205Y-15830D01*
X-1487135Y-16280D01*
X-1488605D01*
G01X-1200000Y-560000D02*
X-890000D01*
G01Y-520000D02*
X-1200000D01*
G01X-575000Y-480000D02*
X-1200000D01*
G01X-1200335Y-180902D02*
X-1201210Y-177902D01*
X-1202085Y-180902D01*
G01X-1201770Y-179852D02*
X-1200650D01*
G01X-1203345Y-179652D02*
X-1203590Y-179302D01*
X-1203800Y-179102D01*
X-1204080Y-179002D01*
X-1204325Y-179102D01*
X-1204500Y-179302D01*
X-1204640Y-179602D01*
X-1204675Y-179952D01*
X-1204640Y-180252D01*
X-1204500Y-180552D01*
X-1204290Y-180802D01*
X-1204045Y-180902D01*
X-1203765Y-180802D01*
X-1203520Y-180502D01*
X-1203380Y-180052D01*
X-1203345Y-179552D01*
X-1203415Y-178902D01*
X-1203520Y-178552D01*
X-1203695Y-178202D01*
X-1203940Y-177952D01*
X-1204185Y-177902D01*
X-1204430Y-178002D01*
X-1204605Y-178252D01*
G01X-1201300Y-159500D02*
X-1199900D01*
Y-156500D01*
X-1201300D01*
G01X-1200740Y-157950D02*
X-1199900D01*
G01X-1202735Y-158250D02*
X-1202980Y-157900D01*
X-1203190Y-157700D01*
X-1203470Y-157600D01*
X-1203715Y-157700D01*
X-1203890Y-157900D01*
X-1204030Y-158200D01*
X-1204065Y-158550D01*
X-1204030Y-158850D01*
X-1203890Y-159150D01*
X-1203680Y-159400D01*
X-1203435Y-159500D01*
X-1203155Y-159400D01*
X-1202910Y-159100D01*
X-1202770Y-158650D01*
X-1202735Y-158150D01*
X-1202805Y-157500D01*
X-1202910Y-157150D01*
X-1203085Y-156800D01*
X-1203330Y-156550D01*
X-1203575Y-156500D01*
X-1203820Y-156600D01*
X-1203995Y-156850D01*
G01X-1200790Y-133807D02*
X-1201630D01*
G01X-1201210D02*
Y-136807D01*
G01X-1200790D02*
X-1201630D01*
G01X-1203345Y-135557D02*
X-1203590Y-135207D01*
X-1203800Y-135007D01*
X-1204080Y-134907D01*
X-1204325Y-135007D01*
X-1204500Y-135207D01*
X-1204640Y-135507D01*
X-1204675Y-135857D01*
X-1204640Y-136157D01*
X-1204500Y-136457D01*
X-1204290Y-136707D01*
X-1204045Y-136807D01*
X-1203765Y-136707D01*
X-1203520Y-136407D01*
X-1203380Y-135957D01*
X-1203345Y-135457D01*
X-1203415Y-134807D01*
X-1203520Y-134457D01*
X-1203695Y-134107D01*
X-1203940Y-133857D01*
X-1204185Y-133807D01*
X-1204430Y-133907D01*
X-1204605Y-134157D01*
G01X-1150260Y-180402D02*
X-1151135Y-177402D01*
X-1152010Y-180402D01*
G01X-1151695Y-179352D02*
X-1150575D01*
G01X-1153935Y-180402D02*
Y-177402D01*
X-1153515Y-178002D01*
G01Y-180402D02*
X-1154355D01*
G01X-1151860Y-156610D02*
X-1150460D01*
Y-153610D01*
X-1151860D01*
G01X-1151300Y-155060D02*
X-1150460D01*
G01X-1153960Y-156610D02*
Y-153610D01*
X-1153540Y-154210D01*
G01Y-156610D02*
X-1154380D01*
G01X-1150740Y-132550D02*
X-1151580D01*
G01X-1151160D02*
Y-135550D01*
G01X-1150740D02*
X-1151580D01*
G01X-1153960D02*
Y-132550D01*
X-1153540Y-133150D01*
G01Y-135550D02*
X-1154380D01*
G01X-1017816Y-180402D02*
X-1018691Y-177402D01*
X-1019566Y-180402D01*
G01X-1019251Y-179352D02*
X-1018131D01*
G01X-1020826Y-179152D02*
X-1021071Y-178802D01*
X-1021281Y-178602D01*
X-1021561Y-178502D01*
X-1021806Y-178602D01*
X-1021981Y-178802D01*
X-1022121Y-179102D01*
X-1022156Y-179452D01*
X-1022121Y-179752D01*
X-1021981Y-180052D01*
X-1021771Y-180302D01*
X-1021526Y-180402D01*
X-1021246Y-180302D01*
X-1021001Y-180002D01*
X-1020861Y-179552D01*
X-1020826Y-179052D01*
X-1020896Y-178402D01*
X-1021001Y-178052D01*
X-1021176Y-177702D01*
X-1021421Y-177452D01*
X-1021666Y-177402D01*
X-1021911Y-177502D01*
X-1022086Y-177752D01*
G01X-1019391Y-158354D02*
X-1017991D01*
Y-155354D01*
X-1019391D01*
G01X-1018831Y-156804D02*
X-1017991D01*
G01X-1020826Y-157104D02*
X-1021071Y-156754D01*
X-1021281Y-156554D01*
X-1021561Y-156454D01*
X-1021806Y-156554D01*
X-1021981Y-156754D01*
X-1022121Y-157054D01*
X-1022156Y-157404D01*
X-1022121Y-157704D01*
X-1021981Y-158004D01*
X-1021771Y-158254D01*
X-1021526Y-158354D01*
X-1021246Y-158254D01*
X-1021001Y-157954D01*
X-1020861Y-157504D01*
X-1020826Y-157004D01*
X-1020896Y-156354D01*
X-1021001Y-156004D01*
X-1021176Y-155654D01*
X-1021421Y-155404D01*
X-1021666Y-155354D01*
X-1021911Y-155454D01*
X-1022086Y-155704D01*
G01X-1018271Y-133307D02*
X-1019110D01*
G01X-1018691D02*
Y-136307D01*
G01X-1018271D02*
X-1019110D01*
G01X-1020826Y-135057D02*
X-1021071Y-134707D01*
X-1021281Y-134507D01*
X-1021561Y-134407D01*
X-1021806Y-134507D01*
X-1021981Y-134707D01*
X-1022121Y-135007D01*
X-1022156Y-135357D01*
X-1022121Y-135657D01*
X-1021981Y-135957D01*
X-1021771Y-136207D01*
X-1021526Y-136307D01*
X-1021246Y-136207D01*
X-1021001Y-135907D01*
X-1020861Y-135457D01*
X-1020826Y-134957D01*
X-1020896Y-134307D01*
X-1021001Y-133957D01*
X-1021176Y-133607D01*
X-1021421Y-133357D01*
X-1021666Y-133307D01*
X-1021911Y-133407D01*
X-1022086Y-133657D01*
G01X-966741Y-180402D02*
X-967616Y-177402D01*
X-968491Y-180402D01*
G01X-968176Y-179352D02*
X-967056D01*
G01X-970416Y-180402D02*
Y-177402D01*
X-969996Y-178002D01*
G01Y-180402D02*
X-970836D01*
G01X-969430Y-156900D02*
X-968030D01*
Y-153900D01*
X-969430D01*
G01X-968870Y-155350D02*
X-968030D01*
G01X-971530Y-156900D02*
Y-153900D01*
X-971110Y-154500D01*
G01Y-156900D02*
X-971950D01*
G01X-967393Y-133307D02*
X-968233D01*
G01X-967813D02*
Y-136307D01*
G01X-967393D02*
X-968233D01*
G01X-970613D02*
Y-133307D01*
X-970193Y-133907D01*
G01Y-136307D02*
X-971033D01*
G01X-927500Y-560000D02*
Y-600000D01*
G01X-915000Y-440000D02*
Y-480000D01*
G01X-890000D02*
Y-600000D01*
G01X-870000Y-440000D02*
Y-480000D01*
G01X-815712Y-99412D02*
X-812712D01*
X-814862Y-100707D01*
Y-98957D01*
G01X-815112Y-83870D02*
X-815462Y-83660D01*
X-815662Y-83380D01*
X-815712Y-83065D01*
X-815662Y-82785D01*
X-815412Y-82505D01*
X-815112Y-82330D01*
X-814812Y-82295D01*
X-814462Y-82365D01*
X-814212Y-82610D01*
X-814112Y-82855D01*
Y-83170D01*
G01Y-82855D02*
X-813962Y-82645D01*
X-813712Y-82470D01*
X-813412Y-82400D01*
X-813112Y-82470D01*
X-812862Y-82645D01*
X-812712Y-82960D01*
X-812762Y-83275D01*
X-812962Y-83590D01*
G01X-799920Y-140000D02*
Y-137000D01*
X-798625Y-139150D01*
X-800375D01*
G01X-776696Y-100300D02*
X-776396Y-100090D01*
X-776246Y-99845D01*
X-776196Y-99565D01*
X-776296Y-99215D01*
X-776546Y-98970D01*
X-776846Y-98900D01*
X-777146Y-98935D01*
X-777396Y-99075D01*
X-777896Y-99775D01*
X-778246Y-100090D01*
X-778746Y-100300D01*
X-779196Y-100370D01*
Y-98900D01*
G01X-680000Y-480000D02*
Y-440000D01*
G01X-330756Y-180402D02*
X-331631Y-177402D01*
X-332507Y-180402D01*
G01X-332191Y-179352D02*
X-331071D01*
G01X-333766Y-179152D02*
X-334011Y-178802D01*
X-334222Y-178602D01*
X-334502Y-178502D01*
X-334747Y-178602D01*
X-334921Y-178802D01*
X-335062Y-179102D01*
X-335097Y-179452D01*
X-335062Y-179752D01*
X-334921Y-180052D01*
X-334711Y-180302D01*
X-334467Y-180402D01*
X-334187Y-180302D01*
X-333942Y-180002D01*
X-333801Y-179552D01*
X-333766Y-179052D01*
X-333836Y-178402D01*
X-333942Y-178052D01*
X-334116Y-177702D01*
X-334361Y-177452D01*
X-334606Y-177402D01*
X-334852Y-177502D01*
X-335027Y-177752D01*
G01X-331440Y-159190D02*
X-330040D01*
Y-156190D01*
X-331440D01*
G01X-330880Y-157640D02*
X-330040D01*
G01X-332875Y-157940D02*
X-333120Y-157590D01*
X-333330Y-157390D01*
X-333610Y-157290D01*
X-333855Y-157390D01*
X-334030Y-157590D01*
X-334170Y-157890D01*
X-334205Y-158240D01*
X-334170Y-158540D01*
X-334030Y-158840D01*
X-333820Y-159090D01*
X-333575Y-159190D01*
X-333295Y-159090D01*
X-333050Y-158790D01*
X-332910Y-158340D01*
X-332875Y-157840D01*
X-332945Y-157190D01*
X-333050Y-156840D01*
X-333225Y-156490D01*
X-333470Y-156240D01*
X-333715Y-156190D01*
X-333960Y-156290D01*
X-334135Y-156540D01*
G01X-331211Y-133307D02*
X-332051D01*
G01X-331631D02*
Y-136307D01*
G01X-331211D02*
X-332051D01*
G01X-333766Y-135057D02*
X-334011Y-134707D01*
X-334222Y-134507D01*
X-334502Y-134407D01*
X-334747Y-134507D01*
X-334921Y-134707D01*
X-335062Y-135007D01*
X-335097Y-135357D01*
X-335062Y-135657D01*
X-334921Y-135957D01*
X-334711Y-136207D01*
X-334467Y-136307D01*
X-334187Y-136207D01*
X-333942Y-135907D01*
X-333801Y-135457D01*
X-333766Y-134957D01*
X-333836Y-134307D01*
X-333942Y-133957D01*
X-334116Y-133607D01*
X-334361Y-133357D01*
X-334606Y-133307D01*
X-334852Y-133407D01*
X-335027Y-133657D01*
G01X-279182Y-180402D02*
X-280057Y-177402D01*
X-280932Y-180402D01*
G01X-280617Y-179352D02*
X-279497D01*
G01X-282857Y-180402D02*
Y-177402D01*
X-282437Y-178002D01*
G01Y-180402D02*
X-283277D01*
G01X-281970Y-156680D02*
X-280570D01*
Y-153680D01*
X-281970D01*
G01X-281410Y-155130D02*
X-280570D01*
G01X-284070Y-156680D02*
Y-153680D01*
X-283650Y-154280D01*
G01Y-156680D02*
X-284490D01*
G01X-280680Y-134500D02*
X-281520D01*
G01X-281100D02*
Y-137500D01*
G01X-280680D02*
X-281520D01*
G01X-283900D02*
Y-134500D01*
X-283480Y-135100D01*
G01Y-137500D02*
X-284320D01*
G01X-148237Y-180402D02*
X-149112Y-177402D01*
X-149987Y-180402D01*
G01X-149672Y-179352D02*
X-148552D01*
G01X-151912Y-180402D02*
X-152157Y-180352D01*
X-152437Y-180202D01*
X-152612Y-179952D01*
X-152682Y-179602D01*
X-152612Y-179252D01*
X-152402Y-178952D01*
X-152087Y-178802D01*
X-151737D01*
X-151527Y-178702D01*
X-151352Y-178452D01*
X-151282Y-178102D01*
X-151387Y-177752D01*
X-151632Y-177502D01*
X-151912Y-177402D01*
X-152192Y-177502D01*
X-152437Y-177752D01*
X-152542Y-178102D01*
X-152472Y-178452D01*
X-152297Y-178702D01*
X-152087Y-178802D01*
X-151737D01*
X-151422Y-178952D01*
X-151212Y-179252D01*
X-151142Y-179602D01*
X-151212Y-179952D01*
X-151387Y-180202D01*
X-151667Y-180352D01*
X-151912Y-180402D01*
G01X-149812Y-158354D02*
X-148412D01*
Y-155354D01*
X-149812D01*
G01X-149252Y-156804D02*
X-148412D01*
G01X-151912Y-158354D02*
X-152157Y-158304D01*
X-152437Y-158154D01*
X-152612Y-157904D01*
X-152682Y-157554D01*
X-152612Y-157204D01*
X-152402Y-156904D01*
X-152087Y-156754D01*
X-151737D01*
X-151527Y-156654D01*
X-151352Y-156404D01*
X-151282Y-156054D01*
X-151387Y-155704D01*
X-151632Y-155454D01*
X-151912Y-155354D01*
X-152192Y-155454D01*
X-152437Y-155704D01*
X-152542Y-156054D01*
X-152472Y-156404D01*
X-152297Y-156654D01*
X-152087Y-156754D01*
X-151737D01*
X-151422Y-156904D01*
X-151212Y-157204D01*
X-151142Y-157554D01*
X-151212Y-157904D01*
X-151387Y-158154D01*
X-151667Y-158304D01*
X-151912Y-158354D01*
G01X-148692Y-133307D02*
X-149532D01*
G01X-149112D02*
Y-136307D01*
G01X-148692D02*
X-149532D01*
G01X-151912D02*
X-152157Y-136257D01*
X-152437Y-136107D01*
X-152612Y-135857D01*
X-152682Y-135507D01*
X-152612Y-135157D01*
X-152402Y-134857D01*
X-152087Y-134707D01*
X-151737D01*
X-151527Y-134607D01*
X-151352Y-134357D01*
X-151282Y-134007D01*
X-151387Y-133657D01*
X-151632Y-133407D01*
X-151912Y-133307D01*
X-152192Y-133407D01*
X-152437Y-133657D01*
X-152542Y-134007D01*
X-152472Y-134357D01*
X-152297Y-134607D01*
X-152087Y-134707D01*
X-151737D01*
X-151422Y-134857D01*
X-151212Y-135157D01*
X-151142Y-135507D01*
X-151212Y-135857D01*
X-151387Y-136107D01*
X-151667Y-136257D01*
X-151912Y-136307D01*
G01X-96662Y-180402D02*
X-97537Y-177402D01*
X-98412Y-180402D01*
G01X-98097Y-179352D02*
X-96977D01*
G01X-100337Y-180402D02*
Y-177402D01*
X-99917Y-178002D01*
G01Y-180402D02*
X-100757D01*
G01X-99240Y-157200D02*
X-97840D01*
Y-154200D01*
X-99240D01*
G01X-98680Y-155650D02*
X-97840D01*
G01X-101340Y-157200D02*
Y-154200D01*
X-100920Y-154800D01*
G01Y-157200D02*
X-101760D01*
G01X-97314Y-133307D02*
X-98154D01*
G01X-97734D02*
Y-136307D01*
G01X-97314D02*
X-98154D01*
G01X-100534D02*
Y-133307D01*
X-100114Y-133907D01*
G01Y-136307D02*
X-100954D01*
G01X-1200000Y-600000D02*
X-575000D01*
Y-440000D01*
X-1200000D01*
Y-600000D01*
G54D15*
G01X-1007500Y-470000D02*
X-1006450Y-475000D01*
X-1005250Y-470000D01*
X-1004050Y-475000D01*
X-1003000Y-470000D01*
G01X-1001125Y-475000D02*
X-999250Y-470000D01*
X-997375Y-475000D01*
G01X-998050Y-473250D02*
X-1000450D01*
G01X-994825Y-474333D02*
X-994225Y-474750D01*
X-993550Y-475000D01*
X-992950D01*
X-992350Y-474750D01*
X-991900Y-474333D01*
X-991675Y-473750D01*
X-991825Y-473167D01*
X-992200Y-472667D01*
X-992875Y-472333D01*
X-993775Y-472167D01*
X-994300Y-471833D01*
X-994525Y-471250D01*
X-994375Y-470667D01*
X-994000Y-470250D01*
X-993475Y-470000D01*
X-992950D01*
X-992425Y-470167D01*
X-991975Y-470583D01*
G01X-988825Y-475000D02*
Y-470000D01*
G01X-985675D02*
Y-475000D01*
G01Y-472500D02*
X-988825D01*
G01X-976525Y-474417D02*
X-976000Y-474833D01*
X-975400Y-475000D01*
X-974800Y-474833D01*
X-974275Y-474333D01*
X-973900Y-473583D01*
X-973750Y-472833D01*
Y-471917D01*
X-973900Y-471167D01*
X-974275Y-470500D01*
X-974725Y-470167D01*
X-975250Y-470000D01*
X-975850Y-470167D01*
X-976300Y-470500D01*
X-976600Y-471000D01*
X-976750Y-471667D01*
X-976600Y-472250D01*
X-976225Y-472833D01*
X-975775Y-473167D01*
X-975250Y-473250D01*
X-974650Y-473083D01*
X-974200Y-472667D01*
X-973750Y-471917D01*
G01X-969250Y-475000D02*
X-968725Y-474917D01*
X-968125Y-474667D01*
X-967750Y-474250D01*
X-967600Y-473667D01*
X-967750Y-473083D01*
X-968200Y-472583D01*
X-968875Y-472333D01*
X-969625D01*
X-970075Y-472167D01*
X-970450Y-471750D01*
X-970600Y-471167D01*
X-970375Y-470583D01*
X-969850Y-470167D01*
X-969250Y-470000D01*
X-968650Y-470167D01*
X-968125Y-470583D01*
X-967900Y-471167D01*
X-968050Y-471750D01*
X-968425Y-472167D01*
X-968875Y-472333D01*
X-969625D01*
X-970300Y-472583D01*
X-970750Y-473083D01*
X-970900Y-473667D01*
X-970750Y-474250D01*
X-970375Y-474667D01*
X-969775Y-474917D01*
X-969250Y-475000D01*
G01X-963250Y-470000D02*
X-963850Y-470167D01*
X-964300Y-470583D01*
X-964600Y-471083D01*
X-964825Y-471750D01*
X-964900Y-472500D01*
X-964825Y-473250D01*
X-964600Y-473917D01*
X-964300Y-474417D01*
X-963850Y-474833D01*
X-963250Y-475000D01*
X-962650Y-474833D01*
X-962200Y-474417D01*
X-961900Y-473917D01*
X-961675Y-473250D01*
X-961600Y-472500D01*
X-961675Y-471750D01*
X-961900Y-471083D01*
X-962200Y-470583D01*
X-962650Y-470167D01*
X-963250Y-470000D01*
G01X-958900Y-474250D02*
X-958450Y-474667D01*
X-957925Y-474917D01*
X-957250Y-475000D01*
X-956575Y-474833D01*
X-956050Y-474500D01*
X-955675Y-473917D01*
X-955600Y-473250D01*
X-955750Y-472583D01*
X-956125Y-472167D01*
X-956650Y-471833D01*
X-957175Y-471750D01*
X-957700Y-471833D01*
X-958375Y-472167D01*
X-958150Y-470000D01*
X-956125D01*
G01X-952675Y-470833D02*
X-952225Y-470333D01*
X-951700Y-470083D01*
X-951100Y-470000D01*
X-950350Y-470167D01*
X-949825Y-470583D01*
X-949675Y-471083D01*
X-949750Y-471583D01*
X-950050Y-472000D01*
X-951550Y-472833D01*
X-952225Y-473417D01*
X-952675Y-474250D01*
X-952825Y-475000D01*
X-949675D01*
G01X-946225Y-473333D02*
X-944275D01*
G01X-940675Y-472917D02*
X-940150Y-472333D01*
X-939700Y-472000D01*
X-939100Y-471833D01*
X-938575Y-472000D01*
X-938200Y-472333D01*
X-937900Y-472833D01*
X-937825Y-473417D01*
X-937900Y-473917D01*
X-938200Y-474417D01*
X-938650Y-474833D01*
X-939175Y-475000D01*
X-939775Y-474833D01*
X-940300Y-474333D01*
X-940600Y-473583D01*
X-940675Y-472750D01*
X-940525Y-471667D01*
X-940300Y-471083D01*
X-939925Y-470500D01*
X-939400Y-470083D01*
X-938875Y-470000D01*
X-938350Y-470167D01*
X-937975Y-470583D01*
G01X-934900Y-474000D02*
X-934450Y-474583D01*
X-933850Y-474917D01*
X-933175Y-475000D01*
X-932575Y-474917D01*
X-931975Y-474500D01*
X-931600Y-474000D01*
X-931525Y-473500D01*
X-931675Y-472917D01*
X-932200Y-472500D01*
X-932725Y-472333D01*
X-933400D01*
G01X-932725D02*
X-932275Y-472083D01*
X-931900Y-471667D01*
X-931750Y-471167D01*
X-931900Y-470667D01*
X-932275Y-470250D01*
X-932950Y-470000D01*
X-933625Y-470083D01*
X-934300Y-470417D01*
G01X-928525Y-474417D02*
X-928000Y-474833D01*
X-927400Y-475000D01*
X-926800Y-474833D01*
X-926275Y-474333D01*
X-925900Y-473583D01*
X-925750Y-472833D01*
Y-471917D01*
X-925900Y-471167D01*
X-926275Y-470500D01*
X-926725Y-470167D01*
X-927250Y-470000D01*
X-927850Y-470167D01*
X-928300Y-470500D01*
X-928600Y-471000D01*
X-928750Y-471667D01*
X-928600Y-472250D01*
X-928225Y-472833D01*
X-927775Y-473167D01*
X-927250Y-473250D01*
X-926650Y-473083D01*
X-926200Y-472667D01*
X-925750Y-471917D01*
G01X-922525Y-474417D02*
X-922000Y-474833D01*
X-921400Y-475000D01*
X-920800Y-474833D01*
X-920275Y-474333D01*
X-919900Y-473583D01*
X-919750Y-472833D01*
Y-471917D01*
X-919900Y-471167D01*
X-920275Y-470500D01*
X-920725Y-470167D01*
X-921250Y-470000D01*
X-921850Y-470167D01*
X-922300Y-470500D01*
X-922600Y-471000D01*
X-922750Y-471667D01*
X-922600Y-472250D01*
X-922225Y-472833D01*
X-921775Y-473167D01*
X-921250Y-473250D01*
X-920650Y-473083D01*
X-920200Y-472667D01*
X-919750Y-471917D01*
G01X-1006750Y-465000D02*
Y-460000D01*
X-1004875D01*
X-1004275Y-460250D01*
X-1003900Y-460583D01*
X-1003750Y-461250D01*
X-1003900Y-461917D01*
X-1004350Y-462333D01*
X-1004875Y-462583D01*
X-1006750D01*
G01X-1004875D02*
X-1003750Y-465000D01*
G01X-997750D02*
X-1000750D01*
Y-460000D01*
X-997750D01*
G01X-998950Y-462417D02*
X-1000750D01*
G01X-994900Y-465000D02*
Y-460000D01*
X-993400D01*
X-992800Y-460250D01*
X-992350Y-460583D01*
X-991975Y-461083D01*
X-991675Y-461667D01*
X-991600Y-462500D01*
X-991675Y-463333D01*
X-991975Y-463917D01*
X-992350Y-464417D01*
X-992800Y-464750D01*
X-993400Y-465000D01*
X-994900D01*
G01X-989200D02*
Y-460000D01*
X-987250Y-464167D01*
X-985300Y-460000D01*
Y-465000D01*
G01X-981250D02*
X-981850Y-464917D01*
X-982375Y-464583D01*
X-982825Y-464083D01*
X-983125Y-463500D01*
X-983275Y-462833D01*
Y-462167D01*
X-983125Y-461500D01*
X-982825Y-460917D01*
X-982375Y-460417D01*
X-981850Y-460083D01*
X-981250Y-460000D01*
X-980650Y-460083D01*
X-980125Y-460417D01*
X-979675Y-460917D01*
X-979375Y-461500D01*
X-979225Y-462167D01*
Y-462833D01*
X-979375Y-463500D01*
X-979675Y-464083D01*
X-980125Y-464583D01*
X-980650Y-464917D01*
X-981250Y-465000D01*
G01X-976975D02*
Y-460000D01*
X-973525Y-465000D01*
Y-460000D01*
G01X-970900Y-465000D02*
Y-460000D01*
X-969400D01*
X-968800Y-460250D01*
X-968350Y-460583D01*
X-967975Y-461083D01*
X-967675Y-461667D01*
X-967600Y-462500D01*
X-967675Y-463333D01*
X-967975Y-463917D01*
X-968350Y-464417D01*
X-968800Y-464750D01*
X-969400Y-465000D01*
X-970900D01*
G01X-1005250Y-455000D02*
Y-450000D01*
X-1006150Y-451000D01*
G01Y-455000D02*
X-1004350D01*
G01X-995200D02*
Y-450000D01*
X-993250Y-454167D01*
X-991300Y-450000D01*
Y-455000D01*
G01X-988150Y-450000D02*
X-986350D01*
G01X-987250D02*
Y-455000D01*
G01X-988150D02*
X-986350D01*
G01X-979600Y-450417D02*
X-980050Y-450167D01*
X-980575Y-450000D01*
X-981175D01*
X-981850Y-450250D01*
X-982375Y-450667D01*
X-982750Y-451167D01*
X-983050Y-452000D01*
X-983125Y-452750D01*
X-982975Y-453500D01*
X-982750Y-454000D01*
X-982300Y-454500D01*
X-981775Y-454833D01*
X-981250Y-455000D01*
X-980725D01*
X-980200Y-454833D01*
X-979750Y-454583D01*
X-979375Y-454250D01*
G01X-976750Y-455000D02*
Y-450000D01*
X-974875D01*
X-974275Y-450250D01*
X-973900Y-450583D01*
X-973750Y-451250D01*
X-973900Y-451917D01*
X-974350Y-452333D01*
X-974875Y-452583D01*
X-976750D01*
G01X-974875D02*
X-973750Y-455000D01*
G01X-969250D02*
X-969850Y-454917D01*
X-970375Y-454583D01*
X-970825Y-454083D01*
X-971125Y-453500D01*
X-971275Y-452833D01*
Y-452167D01*
X-971125Y-451500D01*
X-970825Y-450917D01*
X-970375Y-450417D01*
X-969850Y-450083D01*
X-969250Y-450000D01*
X-968650Y-450083D01*
X-968125Y-450417D01*
X-967675Y-450917D01*
X-967375Y-451500D01*
X-967225Y-452167D01*
Y-452833D01*
X-967375Y-453500D01*
X-967675Y-454083D01*
X-968125Y-454583D01*
X-968650Y-454917D01*
X-969250Y-455000D01*
G01X-964825Y-454333D02*
X-964225Y-454750D01*
X-963550Y-455000D01*
X-962950D01*
X-962350Y-454750D01*
X-961900Y-454333D01*
X-961675Y-453750D01*
X-961825Y-453167D01*
X-962200Y-452667D01*
X-962875Y-452333D01*
X-963775Y-452167D01*
X-964300Y-451833D01*
X-964525Y-451250D01*
X-964375Y-450667D01*
X-964000Y-450250D01*
X-963475Y-450000D01*
X-962950D01*
X-962425Y-450167D01*
X-961975Y-450583D01*
G01X-957250Y-455000D02*
X-957850Y-454917D01*
X-958375Y-454583D01*
X-958825Y-454083D01*
X-959125Y-453500D01*
X-959275Y-452833D01*
Y-452167D01*
X-959125Y-451500D01*
X-958825Y-450917D01*
X-958375Y-450417D01*
X-957850Y-450083D01*
X-957250Y-450000D01*
X-956650Y-450083D01*
X-956125Y-450417D01*
X-955675Y-450917D01*
X-955375Y-451500D01*
X-955225Y-452167D01*
Y-452833D01*
X-955375Y-453500D01*
X-955675Y-454083D01*
X-956125Y-454583D01*
X-956650Y-454917D01*
X-957250Y-455000D01*
G01X-952675D02*
Y-450000D01*
X-949825D01*
G01X-950875Y-452417D02*
X-952675D01*
G01X-945250Y-450000D02*
Y-455000D01*
G01X-946975Y-450000D02*
X-943525D01*
G01X-935500D02*
X-934450Y-455000D01*
X-933250Y-450000D01*
X-932050Y-455000D01*
X-931000Y-450000D01*
G01X-929125Y-455000D02*
X-927250Y-450000D01*
X-925375Y-455000D01*
G01X-926050Y-453250D02*
X-928450D01*
G01X-921250Y-455000D02*
Y-452750D01*
X-922750Y-450000D01*
G01X-919750D02*
X-921250Y-452750D01*
G54D16*
G01X-874510Y-499000D02*
Y-493000D01*
X-871290Y-499000D01*
Y-493000D01*
G01X-867200Y-499000D02*
X-867760Y-498900D01*
X-868250Y-498500D01*
X-868670Y-497900D01*
X-868950Y-497200D01*
X-869090Y-496400D01*
Y-495600D01*
X-868950Y-494800D01*
X-868670Y-494100D01*
X-868250Y-493500D01*
X-867760Y-493100D01*
X-867200Y-493000D01*
X-866640Y-493100D01*
X-866150Y-493500D01*
X-865730Y-494100D01*
X-865450Y-494800D01*
X-865310Y-495600D01*
Y-496400D01*
X-865450Y-497200D01*
X-865730Y-497900D01*
X-866150Y-498500D01*
X-866640Y-498900D01*
X-867200Y-499000D01*
G01X-861500Y-493000D02*
Y-499000D01*
G01X-863110Y-493000D02*
X-859890D01*
G01X-856640D02*
X-854960D01*
G01X-855800D02*
Y-499000D01*
G01X-856640D02*
X-854960D01*
G01X-848560Y-493500D02*
X-848980Y-493200D01*
X-849470Y-493000D01*
X-850030D01*
X-850660Y-493300D01*
X-851150Y-493800D01*
X-851500Y-494400D01*
X-851780Y-495400D01*
X-851850Y-496300D01*
X-851710Y-497200D01*
X-851500Y-497800D01*
X-851080Y-498400D01*
X-850590Y-498800D01*
X-850100Y-499000D01*
X-849610D01*
X-849120Y-498800D01*
X-848700Y-498500D01*
X-848350Y-498100D01*
G01X-843000Y-499000D02*
X-845800D01*
Y-493000D01*
X-843000D01*
G01X-844120Y-495900D02*
X-845800D01*
G01X-833000Y-499000D02*
X-833560Y-498900D01*
X-834050Y-498500D01*
X-834470Y-497900D01*
X-834750Y-497200D01*
X-834890Y-496400D01*
Y-495600D01*
X-834750Y-494800D01*
X-834470Y-494100D01*
X-834050Y-493500D01*
X-833560Y-493100D01*
X-833000Y-493000D01*
X-832440Y-493100D01*
X-831950Y-493500D01*
X-831530Y-494100D01*
X-831250Y-494800D01*
X-831110Y-495600D01*
Y-496400D01*
X-831250Y-497200D01*
X-831530Y-497900D01*
X-831950Y-498500D01*
X-832440Y-498900D01*
X-833000Y-499000D01*
G01X-828630D02*
Y-493000D01*
X-825970D01*
G01X-826950Y-495900D02*
X-828630D01*
G01X-817300Y-499000D02*
Y-493000D01*
X-815620D01*
X-815060Y-493300D01*
X-814640Y-494000D01*
X-814500Y-494800D01*
X-814640Y-495600D01*
X-814990Y-496200D01*
X-815620Y-496500D01*
X-817300D01*
G01X-811600Y-499000D02*
Y-493000D01*
X-809850D01*
X-809290Y-493300D01*
X-808940Y-493700D01*
X-808800Y-494500D01*
X-808940Y-495300D01*
X-809360Y-495800D01*
X-809850Y-496100D01*
X-811600D01*
G01X-809850D02*
X-808800Y-499000D01*
G01X-804500D02*
X-805060Y-498900D01*
X-805550Y-498500D01*
X-805970Y-497900D01*
X-806250Y-497200D01*
X-806390Y-496400D01*
Y-495600D01*
X-806250Y-494800D01*
X-805970Y-494100D01*
X-805550Y-493500D01*
X-805060Y-493100D01*
X-804500Y-493000D01*
X-803940Y-493100D01*
X-803450Y-493500D01*
X-803030Y-494100D01*
X-802750Y-494800D01*
X-802610Y-495600D01*
Y-496400D01*
X-802750Y-497200D01*
X-803030Y-497900D01*
X-803450Y-498500D01*
X-803940Y-498900D01*
X-804500Y-499000D01*
G01X-800200D02*
Y-493000D01*
X-798520D01*
X-797960Y-493300D01*
X-797540Y-494000D01*
X-797400Y-494800D01*
X-797540Y-495600D01*
X-797890Y-496200D01*
X-798520Y-496500D01*
X-800200D01*
G01X-794500Y-499000D02*
Y-493000D01*
X-792750D01*
X-792190Y-493300D01*
X-791840Y-493700D01*
X-791700Y-494500D01*
X-791840Y-495300D01*
X-792260Y-495800D01*
X-792750Y-496100D01*
X-794500D01*
G01X-792750D02*
X-791700Y-499000D01*
G01X-788240Y-493000D02*
X-786560D01*
G01X-787400D02*
Y-499000D01*
G01X-788240D02*
X-786560D01*
G01X-780300D02*
X-783100D01*
Y-493000D01*
X-780300D01*
G01X-781420Y-495900D02*
X-783100D01*
G01X-776000Y-493000D02*
Y-499000D01*
G01X-777610Y-493000D02*
X-774390D01*
G01X-772050Y-499000D02*
X-770300Y-493000D01*
X-768550Y-499000D01*
G01X-769180Y-496900D02*
X-771420D01*
G01X-766000Y-499000D02*
Y-493000D01*
X-764250D01*
X-763690Y-493300D01*
X-763340Y-493700D01*
X-763200Y-494500D01*
X-763340Y-495300D01*
X-763760Y-495800D01*
X-764250Y-496100D01*
X-766000D01*
G01X-764250D02*
X-763200Y-499000D01*
G01X-758900D02*
Y-496300D01*
X-760300Y-493000D01*
G01X-757500D02*
X-758900Y-496300D01*
G01X-748900Y-499000D02*
Y-493000D01*
X-747220D01*
X-746660Y-493300D01*
X-746240Y-494000D01*
X-746100Y-494800D01*
X-746240Y-495600D01*
X-746590Y-496200D01*
X-747220Y-496500D01*
X-748900D01*
G01X-743200Y-499000D02*
Y-493000D01*
X-741450D01*
X-740890Y-493300D01*
X-740540Y-493700D01*
X-740400Y-494500D01*
X-740540Y-495300D01*
X-740960Y-495800D01*
X-741450Y-496100D01*
X-743200D01*
G01X-741450D02*
X-740400Y-499000D01*
G01X-736100D02*
X-736660Y-498900D01*
X-737150Y-498500D01*
X-737570Y-497900D01*
X-737850Y-497200D01*
X-737990Y-496400D01*
Y-495600D01*
X-737850Y-494800D01*
X-737570Y-494100D01*
X-737150Y-493500D01*
X-736660Y-493100D01*
X-736100Y-493000D01*
X-735540Y-493100D01*
X-735050Y-493500D01*
X-734630Y-494100D01*
X-734350Y-494800D01*
X-734210Y-495600D01*
Y-496400D01*
X-734350Y-497200D01*
X-734630Y-497900D01*
X-735050Y-498500D01*
X-735540Y-498900D01*
X-736100Y-499000D01*
G01X-731800D02*
Y-493000D01*
X-730120D01*
X-729560Y-493300D01*
X-729140Y-494000D01*
X-729000Y-494800D01*
X-729140Y-495600D01*
X-729490Y-496200D01*
X-730120Y-496500D01*
X-731800D01*
G01X-723300Y-499000D02*
X-726100D01*
Y-493000D01*
X-723300D01*
G01X-724420Y-495900D02*
X-726100D01*
G01X-720400Y-499000D02*
Y-493000D01*
X-718650D01*
X-718090Y-493300D01*
X-717740Y-493700D01*
X-717600Y-494500D01*
X-717740Y-495300D01*
X-718160Y-495800D01*
X-718650Y-496100D01*
X-720400D01*
G01X-718650D02*
X-717600Y-499000D01*
G01X-713300Y-493000D02*
Y-499000D01*
G01X-714910Y-493000D02*
X-711690D01*
G01X-707600Y-499000D02*
Y-496300D01*
X-709000Y-493000D01*
G01X-706200D02*
X-707600Y-496300D01*
G01X-701900Y-499200D02*
X-702040Y-499100D01*
Y-498900D01*
X-701900Y-498800D01*
X-701760Y-498900D01*
Y-499100D01*
X-701900Y-499200D01*
G01Y-496500D02*
X-702040Y-496400D01*
Y-496200D01*
X-701900Y-496100D01*
X-701760Y-496200D01*
Y-496400D01*
X-701900Y-496500D01*
G54D17*
G01X-1189333Y-572500D02*
Y-565500D01*
X-1187667D01*
X-1187000Y-565850D01*
X-1186500Y-566317D01*
X-1186083Y-567017D01*
X-1185750Y-567833D01*
X-1185667Y-569000D01*
X-1185750Y-570167D01*
X-1186083Y-570983D01*
X-1186500Y-571684D01*
X-1187000Y-572150D01*
X-1187667Y-572500D01*
X-1189333D01*
G01X-1180700D02*
X-1181367Y-572383D01*
X-1181950Y-571917D01*
X-1182450Y-571217D01*
X-1182783Y-570400D01*
X-1182950Y-569467D01*
Y-568533D01*
X-1182783Y-567600D01*
X-1182450Y-566783D01*
X-1181950Y-566083D01*
X-1181367Y-565617D01*
X-1180700Y-565500D01*
X-1180033Y-565617D01*
X-1179450Y-566083D01*
X-1178950Y-566783D01*
X-1178617Y-567600D01*
X-1178450Y-568533D01*
Y-569467D01*
X-1178617Y-570400D01*
X-1178950Y-571217D01*
X-1179450Y-571917D01*
X-1180033Y-572383D01*
X-1180700Y-572500D01*
G01X-1172067Y-566083D02*
X-1172567Y-565733D01*
X-1173150Y-565500D01*
X-1173817D01*
X-1174567Y-565850D01*
X-1175150Y-566433D01*
X-1175567Y-567133D01*
X-1175900Y-568300D01*
X-1175983Y-569350D01*
X-1175817Y-570400D01*
X-1175567Y-571100D01*
X-1175067Y-571800D01*
X-1174483Y-572267D01*
X-1173900Y-572500D01*
X-1173317D01*
X-1172733Y-572267D01*
X-1172233Y-571917D01*
X-1171817Y-571450D01*
G01X-1168933Y-565500D02*
Y-570517D01*
X-1168600Y-571567D01*
X-1167933Y-572267D01*
X-1167100Y-572500D01*
X-1166267Y-572267D01*
X-1165600Y-571567D01*
X-1165267Y-570517D01*
Y-565500D01*
G01X-1162467Y-572500D02*
Y-565500D01*
X-1160300Y-571333D01*
X-1158133Y-565500D01*
Y-572500D01*
G01X-1151833D02*
X-1155167D01*
Y-565500D01*
X-1151833D01*
G01X-1153167Y-568883D02*
X-1155167D01*
G01X-1148617Y-572500D02*
Y-565500D01*
X-1144783Y-572500D01*
Y-565500D01*
G01X-1139900D02*
Y-572500D01*
G01X-1141817Y-565500D02*
X-1137983D01*
G01X-1128217Y-572500D02*
Y-565500D01*
X-1124383Y-572500D01*
Y-565500D01*
G01X-1121333D02*
Y-570517D01*
X-1121000Y-571567D01*
X-1120333Y-572267D01*
X-1119500Y-572500D01*
X-1118667Y-572267D01*
X-1118000Y-571567D01*
X-1117667Y-570517D01*
Y-565500D01*
G01X-1114867Y-572500D02*
Y-565500D01*
X-1112700Y-571333D01*
X-1110533Y-565500D01*
Y-572500D01*
G01X-1105233Y-568767D02*
X-1104900Y-568417D01*
X-1104650Y-567833D01*
X-1104483Y-567017D01*
X-1104650Y-566317D01*
X-1104983Y-565850D01*
X-1105567Y-565500D01*
X-1107817D01*
Y-572500D01*
X-1105067D01*
X-1104483Y-572033D01*
X-1104150Y-571333D01*
X-1103983Y-570517D01*
X-1104150Y-569700D01*
X-1104650Y-569000D01*
X-1105233Y-568767D01*
X-1107817D01*
G01X-1097433Y-572500D02*
X-1100767D01*
Y-565500D01*
X-1097433D01*
G01X-1098767Y-568883D02*
X-1100767D01*
G01X-1093967Y-572500D02*
Y-565500D01*
X-1091883D01*
X-1091217Y-565850D01*
X-1090800Y-566317D01*
X-1090633Y-567250D01*
X-1090800Y-568183D01*
X-1091300Y-568767D01*
X-1091883Y-569117D01*
X-1093967D01*
G01X-1091883D02*
X-1090633Y-572500D01*
G01X-1189250Y-531567D02*
X-1188583Y-532150D01*
X-1187833Y-532500D01*
X-1187167D01*
X-1186500Y-532150D01*
X-1186000Y-531567D01*
X-1185750Y-530750D01*
X-1185917Y-529933D01*
X-1186333Y-529233D01*
X-1187083Y-528767D01*
X-1188083Y-528533D01*
X-1188667Y-528067D01*
X-1188917Y-527250D01*
X-1188750Y-526433D01*
X-1188333Y-525850D01*
X-1187750Y-525500D01*
X-1187167D01*
X-1186583Y-525733D01*
X-1186083Y-526317D01*
G01X-1182450Y-532500D02*
Y-525500D01*
G01X-1178950D02*
Y-532500D01*
G01Y-529000D02*
X-1182450D01*
G01X-1172233Y-532500D02*
X-1175567D01*
Y-525500D01*
X-1172233D01*
G01X-1173567Y-528883D02*
X-1175567D01*
G01X-1165433Y-532500D02*
X-1168767D01*
Y-525500D01*
X-1165433D01*
G01X-1166767Y-528883D02*
X-1168767D01*
G01X-1160300Y-525500D02*
Y-532500D01*
G01X-1162217Y-525500D02*
X-1158383D01*
G01X-1146700D02*
Y-532500D01*
G01X-1148617Y-525500D02*
X-1144783D01*
G01X-1140900D02*
X-1138900D01*
G01X-1139900D02*
Y-532500D01*
G01X-1140900D02*
X-1138900D01*
G01X-1133100Y-525500D02*
Y-532500D01*
G01X-1135017Y-525500D02*
X-1131183D01*
G01X-1127967D02*
Y-532500D01*
X-1124633D01*
G01X-1117833D02*
X-1121167D01*
Y-525500D01*
X-1117833D01*
G01X-1119167Y-528883D02*
X-1121167D01*
G01X-1112700Y-532733D02*
X-1112867Y-532617D01*
Y-532383D01*
X-1112700Y-532267D01*
X-1112533Y-532383D01*
Y-532617D01*
X-1112700Y-532733D01*
G01Y-529584D02*
X-1112867Y-529467D01*
Y-529233D01*
X-1112700Y-529117D01*
X-1112533Y-529233D01*
Y-529467D01*
X-1112700Y-529584D01*
G01X-1187500Y-485500D02*
Y-492500D01*
G01X-1189417Y-485500D02*
X-1185583D01*
G01X-1181700D02*
X-1179700D01*
G01X-1180700D02*
Y-492500D01*
G01X-1181700D02*
X-1179700D01*
G01X-1173900Y-485500D02*
Y-492500D01*
G01X-1175817Y-485500D02*
X-1171983D01*
G01X-1168767D02*
Y-492500D01*
X-1165433D01*
G01X-1158633D02*
X-1161967D01*
Y-485500D01*
X-1158633D01*
G01X-1159967Y-488883D02*
X-1161967D01*
G01X-916667Y-570000D02*
Y-563000D01*
X-914583D01*
X-913917Y-563350D01*
X-913500Y-563817D01*
X-913333Y-564750D01*
X-913500Y-565683D01*
X-914000Y-566267D01*
X-914583Y-566617D01*
X-916667D01*
G01X-914583D02*
X-913333Y-570000D01*
G01X-906533D02*
X-909867D01*
Y-563000D01*
X-906533D01*
G01X-907867Y-566383D02*
X-909867D01*
G01X-903483Y-563000D02*
X-901400Y-570000D01*
X-899317Y-563000D01*
G01X-907850Y-451567D02*
X-907183Y-452150D01*
X-906433Y-452500D01*
X-905767D01*
X-905100Y-452150D01*
X-904600Y-451567D01*
X-904350Y-450750D01*
X-904517Y-449933D01*
X-904933Y-449233D01*
X-905683Y-448767D01*
X-906683Y-448533D01*
X-907267Y-448067D01*
X-907517Y-447250D01*
X-907350Y-446433D01*
X-906933Y-445850D01*
X-906350Y-445500D01*
X-905767D01*
X-905183Y-445733D01*
X-904683Y-446317D01*
G01X-897467Y-446083D02*
X-897967Y-445733D01*
X-898550Y-445500D01*
X-899217D01*
X-899967Y-445850D01*
X-900550Y-446433D01*
X-900967Y-447133D01*
X-901300Y-448300D01*
X-901383Y-449350D01*
X-901217Y-450400D01*
X-900967Y-451100D01*
X-900467Y-451800D01*
X-899883Y-452267D01*
X-899300Y-452500D01*
X-898717D01*
X-898133Y-452267D01*
X-897633Y-451917D01*
X-897217Y-451450D01*
G01X-894583Y-452500D02*
X-892500Y-445500D01*
X-890417Y-452500D01*
G01X-891167Y-450050D02*
X-893833D01*
G01X-887367Y-445500D02*
Y-452500D01*
X-884033D01*
G01X-877233D02*
X-880567D01*
Y-445500D01*
X-877233D01*
G01X-878567Y-448883D02*
X-880567D01*
G01X-874333Y-572500D02*
Y-565500D01*
X-872667D01*
X-872000Y-565850D01*
X-871500Y-566317D01*
X-871083Y-567017D01*
X-870750Y-567833D01*
X-870667Y-569000D01*
X-870750Y-570167D01*
X-871083Y-570983D01*
X-871500Y-571684D01*
X-872000Y-572150D01*
X-872667Y-572500D01*
X-874333D01*
G01X-866700Y-565500D02*
X-864700D01*
G01X-865700D02*
Y-572500D01*
G01X-866700D02*
X-864700D01*
G01X-860650Y-571567D02*
X-859983Y-572150D01*
X-859233Y-572500D01*
X-858567D01*
X-857900Y-572150D01*
X-857400Y-571567D01*
X-857150Y-570750D01*
X-857317Y-569933D01*
X-857733Y-569233D01*
X-858483Y-568767D01*
X-859483Y-568533D01*
X-860067Y-568067D01*
X-860317Y-567250D01*
X-860150Y-566433D01*
X-859733Y-565850D01*
X-859150Y-565500D01*
X-858567D01*
X-857983Y-565733D01*
X-857483Y-566317D01*
G01X-850267Y-566083D02*
X-850767Y-565733D01*
X-851350Y-565500D01*
X-852017D01*
X-852767Y-565850D01*
X-853350Y-566433D01*
X-853767Y-567133D01*
X-854100Y-568300D01*
X-854183Y-569350D01*
X-854017Y-570400D01*
X-853767Y-571100D01*
X-853267Y-571800D01*
X-852683Y-572267D01*
X-852100Y-572500D01*
X-851517D01*
X-850933Y-572267D01*
X-850433Y-571917D01*
X-850017Y-571450D01*
G01X-846967Y-565500D02*
Y-572500D01*
X-843633D01*
G01X-838500D02*
X-839167Y-572383D01*
X-839750Y-571917D01*
X-840250Y-571217D01*
X-840583Y-570400D01*
X-840750Y-569467D01*
Y-568533D01*
X-840583Y-567600D01*
X-840250Y-566783D01*
X-839750Y-566083D01*
X-839167Y-565617D01*
X-838500Y-565500D01*
X-837833Y-565617D01*
X-837250Y-566083D01*
X-836750Y-566783D01*
X-836417Y-567600D01*
X-836250Y-568533D01*
Y-569467D01*
X-836417Y-570400D01*
X-836750Y-571217D01*
X-837250Y-571917D01*
X-837833Y-572383D01*
X-838500Y-572500D01*
G01X-833450Y-571567D02*
X-832783Y-572150D01*
X-832033Y-572500D01*
X-831367D01*
X-830700Y-572150D01*
X-830200Y-571567D01*
X-829950Y-570750D01*
X-830117Y-569933D01*
X-830533Y-569233D01*
X-831283Y-568767D01*
X-832283Y-568533D01*
X-832867Y-568067D01*
X-833117Y-567250D01*
X-832950Y-566433D01*
X-832533Y-565850D01*
X-831950Y-565500D01*
X-831367D01*
X-830783Y-565733D01*
X-830283Y-566317D01*
G01X-823233Y-572500D02*
X-826567D01*
Y-565500D01*
X-823233D01*
G01X-824567Y-568883D02*
X-826567D01*
G01X-819933Y-572500D02*
Y-565500D01*
X-818267D01*
X-817600Y-565850D01*
X-817100Y-566317D01*
X-816683Y-567017D01*
X-816350Y-567833D01*
X-816267Y-569000D01*
X-816350Y-570167D01*
X-816683Y-570983D01*
X-817100Y-571684D01*
X-817600Y-572150D01*
X-818267Y-572500D01*
X-819933D01*
G01X-807000Y-565500D02*
X-805833Y-572500D01*
X-804500Y-565500D01*
X-803167Y-572500D01*
X-802000Y-565500D01*
G01X-798700D02*
X-796700D01*
G01X-797700D02*
Y-572500D01*
G01X-798700D02*
X-796700D01*
G01X-790900Y-565500D02*
Y-572500D01*
G01X-792817Y-565500D02*
X-788983D01*
G01X-785850Y-572500D02*
Y-565500D01*
G01X-782350D02*
Y-572500D01*
G01Y-569000D02*
X-785850D01*
G01X-777300Y-572500D02*
X-777967Y-572383D01*
X-778550Y-571917D01*
X-779050Y-571217D01*
X-779383Y-570400D01*
X-779550Y-569467D01*
Y-568533D01*
X-779383Y-567600D01*
X-779050Y-566783D01*
X-778550Y-566083D01*
X-777967Y-565617D01*
X-777300Y-565500D01*
X-776633Y-565617D01*
X-776050Y-566083D01*
X-775550Y-566783D01*
X-775217Y-567600D01*
X-775050Y-568533D01*
Y-569467D01*
X-775217Y-570400D01*
X-775550Y-571217D01*
X-776050Y-571917D01*
X-776633Y-572383D01*
X-777300Y-572500D01*
G01X-772333Y-565500D02*
Y-570517D01*
X-772000Y-571567D01*
X-771333Y-572267D01*
X-770500Y-572500D01*
X-769667Y-572267D01*
X-769000Y-571567D01*
X-768667Y-570517D01*
Y-565500D01*
G01X-763700D02*
Y-572500D01*
G01X-765617Y-565500D02*
X-761783D01*
G01X-750100D02*
Y-572500D01*
G01X-752017Y-565500D02*
X-748183D01*
G01X-745050Y-572500D02*
Y-565500D01*
G01X-741550D02*
Y-572500D01*
G01Y-569000D02*
X-745050D01*
G01X-734833Y-572500D02*
X-738167D01*
Y-565500D01*
X-734833D01*
G01X-736167Y-568883D02*
X-738167D01*
G01X-724567Y-572500D02*
Y-565500D01*
X-722567D01*
X-721900Y-565850D01*
X-721400Y-566667D01*
X-721233Y-567600D01*
X-721400Y-568533D01*
X-721817Y-569233D01*
X-722567Y-569584D01*
X-724567D01*
G01X-717767Y-572500D02*
Y-565500D01*
X-715683D01*
X-715017Y-565850D01*
X-714600Y-566317D01*
X-714433Y-567250D01*
X-714600Y-568183D01*
X-715100Y-568767D01*
X-715683Y-569117D01*
X-717767D01*
G01X-715683D02*
X-714433Y-572500D01*
G01X-710300Y-565500D02*
X-708300D01*
G01X-709300D02*
Y-572500D01*
G01X-710300D02*
X-708300D01*
G01X-702500D02*
X-703167Y-572383D01*
X-703750Y-571917D01*
X-704250Y-571217D01*
X-704583Y-570400D01*
X-704750Y-569467D01*
Y-568533D01*
X-704583Y-567600D01*
X-704250Y-566783D01*
X-703750Y-566083D01*
X-703167Y-565617D01*
X-702500Y-565500D01*
X-701833Y-565617D01*
X-701250Y-566083D01*
X-700750Y-566783D01*
X-700417Y-567600D01*
X-700250Y-568533D01*
Y-569467D01*
X-700417Y-570400D01*
X-700750Y-571217D01*
X-701250Y-571917D01*
X-701833Y-572383D01*
X-702500Y-572500D01*
G01X-697367D02*
Y-565500D01*
X-695283D01*
X-694617Y-565850D01*
X-694200Y-566317D01*
X-694033Y-567250D01*
X-694200Y-568183D01*
X-694700Y-568767D01*
X-695283Y-569117D01*
X-697367D01*
G01X-695283D02*
X-694033Y-572500D01*
G01X-684600Y-565500D02*
X-683433Y-572500D01*
X-682100Y-565500D01*
X-680767Y-572500D01*
X-679600Y-565500D01*
G01X-676967Y-572500D02*
Y-565500D01*
X-674883D01*
X-674217Y-565850D01*
X-673800Y-566317D01*
X-673633Y-567250D01*
X-673800Y-568183D01*
X-674300Y-568767D01*
X-674883Y-569117D01*
X-676967D01*
G01X-674883D02*
X-673633Y-572500D01*
G01X-669500Y-565500D02*
X-667500D01*
G01X-668500D02*
Y-572500D01*
G01X-669500D02*
X-667500D01*
G01X-661700Y-565500D02*
Y-572500D01*
G01X-663617Y-565500D02*
X-659783D01*
G01X-654900D02*
Y-572500D01*
G01X-656817Y-565500D02*
X-652983D01*
G01X-646433Y-572500D02*
X-649767D01*
Y-565500D01*
X-646433D01*
G01X-647767Y-568883D02*
X-649767D01*
G01X-643217Y-572500D02*
Y-565500D01*
X-639383Y-572500D01*
Y-565500D01*
G01X-625867Y-566083D02*
X-626367Y-565733D01*
X-626950Y-565500D01*
X-627617D01*
X-628367Y-565850D01*
X-628950Y-566433D01*
X-629367Y-567133D01*
X-629700Y-568300D01*
X-629783Y-569350D01*
X-629617Y-570400D01*
X-629367Y-571100D01*
X-628867Y-571800D01*
X-628283Y-572267D01*
X-627700Y-572500D01*
X-627117D01*
X-626533Y-572267D01*
X-626033Y-571917D01*
X-625617Y-571450D01*
G01X-620900Y-572500D02*
X-621567Y-572383D01*
X-622150Y-571917D01*
X-622650Y-571217D01*
X-622983Y-570400D01*
X-623150Y-569467D01*
Y-568533D01*
X-622983Y-567600D01*
X-622650Y-566783D01*
X-622150Y-566083D01*
X-621567Y-565617D01*
X-620900Y-565500D01*
X-620233Y-565617D01*
X-619650Y-566083D01*
X-619150Y-566783D01*
X-618817Y-567600D01*
X-618650Y-568533D01*
Y-569467D01*
X-618817Y-570400D01*
X-619150Y-571217D01*
X-619650Y-571917D01*
X-620233Y-572383D01*
X-620900Y-572500D01*
G01X-616017D02*
Y-565500D01*
X-612183Y-572500D01*
Y-565500D01*
G01X-609050Y-571567D02*
X-608383Y-572150D01*
X-607633Y-572500D01*
X-606967D01*
X-606300Y-572150D01*
X-605800Y-571567D01*
X-605550Y-570750D01*
X-605717Y-569933D01*
X-606133Y-569233D01*
X-606883Y-568767D01*
X-607883Y-568533D01*
X-608467Y-568067D01*
X-608717Y-567250D01*
X-608550Y-566433D01*
X-608133Y-565850D01*
X-607550Y-565500D01*
X-606967D01*
X-606383Y-565733D01*
X-605883Y-566317D01*
G01X-598833Y-572500D02*
X-602167D01*
Y-565500D01*
X-598833D01*
G01X-600167Y-568883D02*
X-602167D01*
G01X-595617Y-572500D02*
Y-565500D01*
X-591783Y-572500D01*
Y-565500D01*
G01X-586900D02*
Y-572500D01*
G01X-588817Y-565500D02*
X-584983D01*
G01X-872500Y-587500D02*
X-873167Y-587383D01*
X-873750Y-586917D01*
X-874250Y-586217D01*
X-874583Y-585400D01*
X-874750Y-584467D01*
Y-583533D01*
X-874583Y-582600D01*
X-874250Y-581783D01*
X-873750Y-581083D01*
X-873167Y-580617D01*
X-872500Y-580500D01*
X-871833Y-580617D01*
X-871250Y-581083D01*
X-870750Y-581783D01*
X-870417Y-582600D01*
X-870250Y-583533D01*
Y-584467D01*
X-870417Y-585400D01*
X-870750Y-586217D01*
X-871250Y-586917D01*
X-871833Y-587383D01*
X-872500Y-587500D01*
G01X-867283D02*
Y-580500D01*
X-864117D01*
G01X-865283Y-583883D02*
X-867283D01*
G01X-854267Y-587500D02*
Y-580500D01*
X-852100Y-586333D01*
X-849933Y-580500D01*
Y-587500D01*
G01X-846300Y-580500D02*
X-844300D01*
G01X-845300D02*
Y-587500D01*
G01X-846300D02*
X-844300D01*
G01X-836667Y-581083D02*
X-837167Y-580733D01*
X-837750Y-580500D01*
X-838417D01*
X-839167Y-580850D01*
X-839750Y-581433D01*
X-840167Y-582133D01*
X-840500Y-583300D01*
X-840583Y-584350D01*
X-840417Y-585400D01*
X-840167Y-586100D01*
X-839667Y-586800D01*
X-839083Y-587267D01*
X-838500Y-587500D01*
X-837917D01*
X-837333Y-587267D01*
X-836833Y-586917D01*
X-836417Y-586450D01*
G01X-833367Y-587500D02*
Y-580500D01*
X-831283D01*
X-830617Y-580850D01*
X-830200Y-581317D01*
X-830033Y-582250D01*
X-830200Y-583183D01*
X-830700Y-583767D01*
X-831283Y-584117D01*
X-833367D01*
G01X-831283D02*
X-830033Y-587500D01*
G01X-824900D02*
X-825567Y-587383D01*
X-826150Y-586917D01*
X-826650Y-586217D01*
X-826983Y-585400D01*
X-827150Y-584467D01*
Y-583533D01*
X-826983Y-582600D01*
X-826650Y-581783D01*
X-826150Y-581083D01*
X-825567Y-580617D01*
X-824900Y-580500D01*
X-824233Y-580617D01*
X-823650Y-581083D01*
X-823150Y-581783D01*
X-822817Y-582600D01*
X-822650Y-583533D01*
Y-584467D01*
X-822817Y-585400D01*
X-823150Y-586217D01*
X-823650Y-586917D01*
X-824233Y-587383D01*
X-824900Y-587500D01*
G01X-819850Y-586567D02*
X-819183Y-587150D01*
X-818433Y-587500D01*
X-817767D01*
X-817100Y-587150D01*
X-816600Y-586567D01*
X-816350Y-585750D01*
X-816517Y-584933D01*
X-816933Y-584233D01*
X-817683Y-583767D01*
X-818683Y-583533D01*
X-819267Y-583067D01*
X-819517Y-582250D01*
X-819350Y-581433D01*
X-818933Y-580850D01*
X-818350Y-580500D01*
X-817767D01*
X-817183Y-580733D01*
X-816683Y-581317D01*
G01X-811300Y-587500D02*
X-811967Y-587383D01*
X-812550Y-586917D01*
X-813050Y-586217D01*
X-813383Y-585400D01*
X-813550Y-584467D01*
Y-583533D01*
X-813383Y-582600D01*
X-813050Y-581783D01*
X-812550Y-581083D01*
X-811967Y-580617D01*
X-811300Y-580500D01*
X-810633Y-580617D01*
X-810050Y-581083D01*
X-809550Y-581783D01*
X-809217Y-582600D01*
X-809050Y-583533D01*
Y-584467D01*
X-809217Y-585400D01*
X-809550Y-586217D01*
X-810050Y-586917D01*
X-810633Y-587383D01*
X-811300Y-587500D01*
G01X-806083D02*
Y-580500D01*
X-802917D01*
G01X-804083Y-583883D02*
X-806083D01*
G01X-797700Y-580500D02*
Y-587500D01*
G01X-799617Y-580500D02*
X-795783D01*
G01X-782267Y-581083D02*
X-782767Y-580733D01*
X-783350Y-580500D01*
X-784017D01*
X-784767Y-580850D01*
X-785350Y-581433D01*
X-785767Y-582133D01*
X-786100Y-583300D01*
X-786183Y-584350D01*
X-786017Y-585400D01*
X-785767Y-586100D01*
X-785267Y-586800D01*
X-784683Y-587267D01*
X-784100Y-587500D01*
X-783517D01*
X-782933Y-587267D01*
X-782433Y-586917D01*
X-782017Y-586450D01*
G01X-777300Y-587500D02*
X-777967Y-587383D01*
X-778550Y-586917D01*
X-779050Y-586217D01*
X-779383Y-585400D01*
X-779550Y-584467D01*
Y-583533D01*
X-779383Y-582600D01*
X-779050Y-581783D01*
X-778550Y-581083D01*
X-777967Y-580617D01*
X-777300Y-580500D01*
X-776633Y-580617D01*
X-776050Y-581083D01*
X-775550Y-581783D01*
X-775217Y-582600D01*
X-775050Y-583533D01*
Y-584467D01*
X-775217Y-585400D01*
X-775550Y-586217D01*
X-776050Y-586917D01*
X-776633Y-587383D01*
X-777300Y-587500D01*
G01X-772167D02*
Y-580500D01*
X-770083D01*
X-769417Y-580850D01*
X-769000Y-581317D01*
X-768833Y-582250D01*
X-769000Y-583183D01*
X-769500Y-583767D01*
X-770083Y-584117D01*
X-772167D01*
G01X-770083D02*
X-768833Y-587500D01*
G01X-765367D02*
Y-580500D01*
X-763367D01*
X-762700Y-580850D01*
X-762200Y-581667D01*
X-762033Y-582600D01*
X-762200Y-583533D01*
X-762617Y-584233D01*
X-763367Y-584584D01*
X-765367D01*
G01X-756900Y-587500D02*
X-757567Y-587383D01*
X-758150Y-586917D01*
X-758650Y-586217D01*
X-758983Y-585400D01*
X-759150Y-584467D01*
Y-583533D01*
X-758983Y-582600D01*
X-758650Y-581783D01*
X-758150Y-581083D01*
X-757567Y-580617D01*
X-756900Y-580500D01*
X-756233Y-580617D01*
X-755650Y-581083D01*
X-755150Y-581783D01*
X-754817Y-582600D01*
X-754650Y-583533D01*
Y-584467D01*
X-754817Y-585400D01*
X-755150Y-586217D01*
X-755650Y-586917D01*
X-756233Y-587383D01*
X-756900Y-587500D01*
G01X-751767D02*
Y-580500D01*
X-749683D01*
X-749017Y-580850D01*
X-748600Y-581317D01*
X-748433Y-582250D01*
X-748600Y-583183D01*
X-749100Y-583767D01*
X-749683Y-584117D01*
X-751767D01*
G01X-749683D02*
X-748433Y-587500D01*
G01X-745383D02*
X-743300Y-580500D01*
X-741217Y-587500D01*
G01X-741967Y-585050D02*
X-744633D01*
G01X-736500Y-580500D02*
Y-587500D01*
G01X-738417Y-580500D02*
X-734583D01*
G01X-730700D02*
X-728700D01*
G01X-729700D02*
Y-587500D01*
G01X-730700D02*
X-728700D01*
G01X-722900D02*
X-723567Y-587383D01*
X-724150Y-586917D01*
X-724650Y-586217D01*
X-724983Y-585400D01*
X-725150Y-584467D01*
Y-583533D01*
X-724983Y-582600D01*
X-724650Y-581783D01*
X-724150Y-581083D01*
X-723567Y-580617D01*
X-722900Y-580500D01*
X-722233Y-580617D01*
X-721650Y-581083D01*
X-721150Y-581783D01*
X-720817Y-582600D01*
X-720650Y-583533D01*
Y-584467D01*
X-720817Y-585400D01*
X-721150Y-586217D01*
X-721650Y-586917D01*
X-722233Y-587383D01*
X-722900Y-587500D01*
G01X-718017D02*
Y-580500D01*
X-714183Y-587500D01*
Y-580500D01*
G01X-709300Y-587733D02*
X-709467Y-587617D01*
Y-587383D01*
X-709300Y-587267D01*
X-709133Y-587383D01*
Y-587617D01*
X-709300Y-587733D01*
G01X-870667Y-551083D02*
X-871167Y-550733D01*
X-871750Y-550500D01*
X-872417D01*
X-873167Y-550850D01*
X-873750Y-551433D01*
X-874167Y-552133D01*
X-874500Y-553300D01*
X-874583Y-554350D01*
X-874417Y-555400D01*
X-874167Y-556100D01*
X-873667Y-556800D01*
X-873083Y-557267D01*
X-872500Y-557500D01*
X-871917D01*
X-871333Y-557267D01*
X-870833Y-556917D01*
X-870417Y-556450D01*
G01X-865700Y-557500D02*
X-866367Y-557383D01*
X-866950Y-556917D01*
X-867450Y-556217D01*
X-867783Y-555400D01*
X-867950Y-554467D01*
Y-553533D01*
X-867783Y-552600D01*
X-867450Y-551783D01*
X-866950Y-551083D01*
X-866367Y-550617D01*
X-865700Y-550500D01*
X-865033Y-550617D01*
X-864450Y-551083D01*
X-863950Y-551783D01*
X-863617Y-552600D01*
X-863450Y-553533D01*
Y-554467D01*
X-863617Y-555400D01*
X-863950Y-556217D01*
X-864450Y-556917D01*
X-865033Y-557383D01*
X-865700Y-557500D01*
G01X-860817D02*
Y-550500D01*
X-856983Y-557500D01*
Y-550500D01*
G01X-853683Y-557500D02*
Y-550500D01*
X-850517D01*
G01X-851683Y-553883D02*
X-853683D01*
G01X-846300Y-550500D02*
X-844300D01*
G01X-845300D02*
Y-557500D01*
G01X-846300D02*
X-844300D01*
G01X-840333D02*
Y-550500D01*
X-838667D01*
X-838000Y-550850D01*
X-837500Y-551317D01*
X-837083Y-552017D01*
X-836750Y-552833D01*
X-836667Y-554000D01*
X-836750Y-555167D01*
X-837083Y-555983D01*
X-837500Y-556684D01*
X-838000Y-557150D01*
X-838667Y-557500D01*
X-840333D01*
G01X-830033D02*
X-833367D01*
Y-550500D01*
X-830033D01*
G01X-831367Y-553883D02*
X-833367D01*
G01X-826817Y-557500D02*
Y-550500D01*
X-822983Y-557500D01*
Y-550500D01*
G01X-816267Y-551083D02*
X-816767Y-550733D01*
X-817350Y-550500D01*
X-818017D01*
X-818767Y-550850D01*
X-819350Y-551433D01*
X-819767Y-552133D01*
X-820100Y-553300D01*
X-820183Y-554350D01*
X-820017Y-555400D01*
X-819767Y-556100D01*
X-819267Y-556800D01*
X-818683Y-557267D01*
X-818100Y-557500D01*
X-817517D01*
X-816933Y-557267D01*
X-816433Y-556917D01*
X-816017Y-556450D01*
G01X-809633Y-557500D02*
X-812967D01*
Y-550500D01*
X-809633D01*
G01X-810967Y-553883D02*
X-812967D01*
G01X-799783Y-557500D02*
X-797700Y-550500D01*
X-795617Y-557500D01*
G01X-796367Y-555050D02*
X-799033D01*
G01X-792817Y-557500D02*
Y-550500D01*
X-788983Y-557500D01*
Y-550500D01*
G01X-785933Y-557500D02*
Y-550500D01*
X-784267D01*
X-783600Y-550850D01*
X-783100Y-551317D01*
X-782683Y-552017D01*
X-782350Y-552833D01*
X-782267Y-554000D01*
X-782350Y-555167D01*
X-782683Y-555983D01*
X-783100Y-556684D01*
X-783600Y-557150D01*
X-784267Y-557500D01*
X-785933D01*
G01X-771500Y-550500D02*
X-769500D01*
G01X-770500D02*
Y-557500D01*
G01X-771500D02*
X-769500D01*
G01X-763700Y-550500D02*
Y-557500D01*
G01X-765617Y-550500D02*
X-761783D01*
G01X-758650Y-556567D02*
X-757983Y-557150D01*
X-757233Y-557500D01*
X-756567D01*
X-755900Y-557150D01*
X-755400Y-556567D01*
X-755150Y-555750D01*
X-755317Y-554933D01*
X-755733Y-554233D01*
X-756483Y-553767D01*
X-757483Y-553533D01*
X-758067Y-553067D01*
X-758317Y-552250D01*
X-758150Y-551433D01*
X-757733Y-550850D01*
X-757150Y-550500D01*
X-756567D01*
X-755983Y-550733D01*
X-755483Y-551317D01*
G01X-741467Y-551083D02*
X-741967Y-550733D01*
X-742550Y-550500D01*
X-743217D01*
X-743967Y-550850D01*
X-744550Y-551433D01*
X-744967Y-552133D01*
X-745300Y-553300D01*
X-745383Y-554350D01*
X-745217Y-555400D01*
X-744967Y-556100D01*
X-744467Y-556800D01*
X-743883Y-557267D01*
X-743300Y-557500D01*
X-742717D01*
X-742133Y-557267D01*
X-741633Y-556917D01*
X-741217Y-556450D01*
G01X-736500Y-557500D02*
X-737167Y-557383D01*
X-737750Y-556917D01*
X-738250Y-556217D01*
X-738583Y-555400D01*
X-738750Y-554467D01*
Y-553533D01*
X-738583Y-552600D01*
X-738250Y-551783D01*
X-737750Y-551083D01*
X-737167Y-550617D01*
X-736500Y-550500D01*
X-735833Y-550617D01*
X-735250Y-551083D01*
X-734750Y-551783D01*
X-734417Y-552600D01*
X-734250Y-553533D01*
Y-554467D01*
X-734417Y-555400D01*
X-734750Y-556217D01*
X-735250Y-556917D01*
X-735833Y-557383D01*
X-736500Y-557500D01*
G01X-731617D02*
Y-550500D01*
X-727783Y-557500D01*
Y-550500D01*
G01X-722900D02*
Y-557500D01*
G01X-724817Y-550500D02*
X-720983D01*
G01X-714433Y-557500D02*
X-717767D01*
Y-550500D01*
X-714433D01*
G01X-715767Y-553883D02*
X-717767D01*
G01X-711217Y-557500D02*
Y-550500D01*
X-707383Y-557500D01*
Y-550500D01*
G01X-702500D02*
Y-557500D01*
G01X-704417Y-550500D02*
X-700583D01*
G01X-697450Y-556567D02*
X-696783Y-557150D01*
X-696033Y-557500D01*
X-695367D01*
X-694700Y-557150D01*
X-694200Y-556567D01*
X-693950Y-555750D01*
X-694117Y-554933D01*
X-694533Y-554233D01*
X-695283Y-553767D01*
X-696283Y-553533D01*
X-696867Y-553067D01*
X-697117Y-552250D01*
X-696950Y-551433D01*
X-696533Y-550850D01*
X-695950Y-550500D01*
X-695367D01*
X-694783Y-550733D01*
X-694283Y-551317D01*
G01X-684267Y-557500D02*
Y-550500D01*
X-682100Y-556333D01*
X-679933Y-550500D01*
Y-557500D01*
G01X-677383D02*
X-675300Y-550500D01*
X-673217Y-557500D01*
G01X-673967Y-555050D02*
X-676633D01*
G01X-668500Y-557500D02*
Y-554350D01*
X-670167Y-550500D01*
G01X-666833D02*
X-668500Y-554350D01*
G01X-656817Y-557500D02*
Y-550500D01*
X-652983Y-557500D01*
Y-550500D01*
G01X-648100Y-557500D02*
X-648767Y-557383D01*
X-649350Y-556917D01*
X-649850Y-556217D01*
X-650183Y-555400D01*
X-650350Y-554467D01*
Y-553533D01*
X-650183Y-552600D01*
X-649850Y-551783D01*
X-649350Y-551083D01*
X-648767Y-550617D01*
X-648100Y-550500D01*
X-647433Y-550617D01*
X-646850Y-551083D01*
X-646350Y-551783D01*
X-646017Y-552600D01*
X-645850Y-553533D01*
Y-554467D01*
X-646017Y-555400D01*
X-646350Y-556217D01*
X-646850Y-556917D01*
X-647433Y-557383D01*
X-648100Y-557500D01*
G01X-641300Y-550500D02*
Y-557500D01*
G01X-643217Y-550500D02*
X-639383D01*
G01X-627033Y-553767D02*
X-626700Y-553417D01*
X-626450Y-552833D01*
X-626283Y-552017D01*
X-626450Y-551317D01*
X-626783Y-550850D01*
X-627367Y-550500D01*
X-629617D01*
Y-557500D01*
X-626867D01*
X-626283Y-557033D01*
X-625950Y-556333D01*
X-625783Y-555517D01*
X-625950Y-554700D01*
X-626450Y-554000D01*
X-627033Y-553767D01*
X-629617D01*
G01X-619233Y-557500D02*
X-622567D01*
Y-550500D01*
X-619233D01*
G01X-620567Y-553883D02*
X-622567D01*
G01X-870667Y-536083D02*
X-871167Y-535733D01*
X-871750Y-535500D01*
X-872417D01*
X-873167Y-535850D01*
X-873750Y-536433D01*
X-874167Y-537133D01*
X-874500Y-538300D01*
X-874583Y-539350D01*
X-874417Y-540400D01*
X-874167Y-541100D01*
X-873667Y-541800D01*
X-873083Y-542267D01*
X-872500Y-542500D01*
X-871917D01*
X-871333Y-542267D01*
X-870833Y-541917D01*
X-870417Y-541450D01*
G01X-865700Y-542500D02*
X-866367Y-542383D01*
X-866950Y-541917D01*
X-867450Y-541217D01*
X-867783Y-540400D01*
X-867950Y-539467D01*
Y-538533D01*
X-867783Y-537600D01*
X-867450Y-536783D01*
X-866950Y-536083D01*
X-866367Y-535617D01*
X-865700Y-535500D01*
X-865033Y-535617D01*
X-864450Y-536083D01*
X-863950Y-536783D01*
X-863617Y-537600D01*
X-863450Y-538533D01*
Y-539467D01*
X-863617Y-540400D01*
X-863950Y-541217D01*
X-864450Y-541917D01*
X-865033Y-542383D01*
X-865700Y-542500D01*
G01X-860567D02*
Y-535500D01*
X-858483D01*
X-857817Y-535850D01*
X-857400Y-536317D01*
X-857233Y-537250D01*
X-857400Y-538183D01*
X-857900Y-538767D01*
X-858483Y-539117D01*
X-860567D01*
G01X-858483D02*
X-857233Y-542500D01*
G01X-853767D02*
Y-535500D01*
X-851767D01*
X-851100Y-535850D01*
X-850600Y-536667D01*
X-850433Y-537600D01*
X-850600Y-538533D01*
X-851017Y-539233D01*
X-851767Y-539584D01*
X-853767D01*
G01X-845300Y-542500D02*
X-845967Y-542383D01*
X-846550Y-541917D01*
X-847050Y-541217D01*
X-847383Y-540400D01*
X-847550Y-539467D01*
Y-538533D01*
X-847383Y-537600D01*
X-847050Y-536783D01*
X-846550Y-536083D01*
X-845967Y-535617D01*
X-845300Y-535500D01*
X-844633Y-535617D01*
X-844050Y-536083D01*
X-843550Y-536783D01*
X-843217Y-537600D01*
X-843050Y-538533D01*
Y-539467D01*
X-843217Y-540400D01*
X-843550Y-541217D01*
X-844050Y-541917D01*
X-844633Y-542383D01*
X-845300Y-542500D01*
G01X-840167D02*
Y-535500D01*
X-838083D01*
X-837417Y-535850D01*
X-837000Y-536317D01*
X-836833Y-537250D01*
X-837000Y-538183D01*
X-837500Y-538767D01*
X-838083Y-539117D01*
X-840167D01*
G01X-838083D02*
X-836833Y-542500D01*
G01X-833783D02*
X-831700Y-535500D01*
X-829617Y-542500D01*
G01X-830367Y-540050D02*
X-833033D01*
G01X-824900Y-535500D02*
Y-542500D01*
G01X-826817Y-535500D02*
X-822983D01*
G01X-819100D02*
X-817100D01*
G01X-818100D02*
Y-542500D01*
G01X-819100D02*
X-817100D01*
G01X-811300D02*
X-811967Y-542383D01*
X-812550Y-541917D01*
X-813050Y-541217D01*
X-813383Y-540400D01*
X-813550Y-539467D01*
Y-538533D01*
X-813383Y-537600D01*
X-813050Y-536783D01*
X-812550Y-536083D01*
X-811967Y-535617D01*
X-811300Y-535500D01*
X-810633Y-535617D01*
X-810050Y-536083D01*
X-809550Y-536783D01*
X-809217Y-537600D01*
X-809050Y-538533D01*
Y-539467D01*
X-809217Y-540400D01*
X-809550Y-541217D01*
X-810050Y-541917D01*
X-810633Y-542383D01*
X-811300Y-542500D01*
G01X-806417D02*
Y-535500D01*
X-802583Y-542500D01*
Y-535500D01*
G01X-797700Y-542733D02*
X-797867Y-542617D01*
Y-542383D01*
X-797700Y-542267D01*
X-797533Y-542383D01*
Y-542617D01*
X-797700Y-542733D01*
G01X-784100Y-535500D02*
Y-542500D01*
G01X-786017Y-535500D02*
X-782183D01*
G01X-779050Y-542500D02*
Y-535500D01*
G01X-775550D02*
Y-542500D01*
G01Y-539000D02*
X-779050D01*
G01X-771500Y-535500D02*
X-769500D01*
G01X-770500D02*
Y-542500D01*
G01X-771500D02*
X-769500D01*
G01X-765450Y-541567D02*
X-764783Y-542150D01*
X-764033Y-542500D01*
X-763367D01*
X-762700Y-542150D01*
X-762200Y-541567D01*
X-761950Y-540750D01*
X-762117Y-539933D01*
X-762533Y-539233D01*
X-763283Y-538767D01*
X-764283Y-538533D01*
X-764867Y-538067D01*
X-765117Y-537250D01*
X-764950Y-536433D01*
X-764533Y-535850D01*
X-763950Y-535500D01*
X-763367D01*
X-762783Y-535733D01*
X-762283Y-536317D01*
G01X-751933Y-542500D02*
Y-535500D01*
X-750267D01*
X-749600Y-535850D01*
X-749100Y-536317D01*
X-748683Y-537017D01*
X-748350Y-537833D01*
X-748267Y-539000D01*
X-748350Y-540167D01*
X-748683Y-540983D01*
X-749100Y-541684D01*
X-749600Y-542150D01*
X-750267Y-542500D01*
X-751933D01*
G01X-744967D02*
Y-535500D01*
X-742883D01*
X-742217Y-535850D01*
X-741800Y-536317D01*
X-741633Y-537250D01*
X-741800Y-538183D01*
X-742300Y-538767D01*
X-742883Y-539117D01*
X-744967D01*
G01X-742883D02*
X-741633Y-542500D01*
G01X-738583D02*
X-736500Y-535500D01*
X-734417Y-542500D01*
G01X-735167Y-540050D02*
X-737833D01*
G01X-732200Y-535500D02*
X-731033Y-542500D01*
X-729700Y-535500D01*
X-728367Y-542500D01*
X-727200Y-535500D01*
G01X-723900D02*
X-721900D01*
G01X-722900D02*
Y-542500D01*
G01X-723900D02*
X-721900D01*
G01X-718017D02*
Y-535500D01*
X-714183Y-542500D01*
Y-535500D01*
G01X-708800Y-539000D02*
X-707133D01*
Y-541100D01*
X-707633Y-541800D01*
X-708217Y-542267D01*
X-709050Y-542500D01*
X-709883Y-542267D01*
X-710467Y-541800D01*
X-710967Y-541100D01*
X-711300Y-540283D01*
X-711467Y-539350D01*
Y-538533D01*
X-711300Y-537833D01*
X-710967Y-537017D01*
X-710467Y-536317D01*
X-709967Y-535850D01*
X-709300Y-535500D01*
X-708717D01*
X-708050Y-535733D01*
X-707550Y-536200D01*
G01X-696700Y-535500D02*
X-694700D01*
G01X-695700D02*
Y-542500D01*
G01X-696700D02*
X-694700D01*
G01X-690650Y-541567D02*
X-689983Y-542150D01*
X-689233Y-542500D01*
X-688567D01*
X-687900Y-542150D01*
X-687400Y-541567D01*
X-687150Y-540750D01*
X-687317Y-539933D01*
X-687733Y-539233D01*
X-688483Y-538767D01*
X-689483Y-538533D01*
X-690067Y-538067D01*
X-690317Y-537250D01*
X-690150Y-536433D01*
X-689733Y-535850D01*
X-689150Y-535500D01*
X-688567D01*
X-687983Y-535733D01*
X-687483Y-536317D01*
G01X-676967Y-542500D02*
Y-535500D01*
X-674883D01*
X-674217Y-535850D01*
X-673800Y-536317D01*
X-673633Y-537250D01*
X-673800Y-538183D01*
X-674300Y-538767D01*
X-674883Y-539117D01*
X-676967D01*
G01X-674883D02*
X-673633Y-542500D01*
G01X-666833D02*
X-670167D01*
Y-535500D01*
X-666833D01*
G01X-668167Y-538883D02*
X-670167D01*
G01X-659867Y-536083D02*
X-660367Y-535733D01*
X-660950Y-535500D01*
X-661617D01*
X-662367Y-535850D01*
X-662950Y-536433D01*
X-663367Y-537133D01*
X-663700Y-538300D01*
X-663783Y-539350D01*
X-663617Y-540400D01*
X-663367Y-541100D01*
X-662867Y-541800D01*
X-662283Y-542267D01*
X-661700Y-542500D01*
X-661117D01*
X-660533Y-542267D01*
X-660033Y-541917D01*
X-659617Y-541450D01*
G01X-653233Y-542500D02*
X-656567D01*
Y-535500D01*
X-653233D01*
G01X-654567Y-538883D02*
X-656567D01*
G01X-649100Y-535500D02*
X-647100D01*
G01X-648100D02*
Y-542500D01*
G01X-649100D02*
X-647100D01*
G01X-643383Y-535500D02*
X-641300Y-542500D01*
X-639217Y-535500D01*
G01X-632833Y-542500D02*
X-636167D01*
Y-535500D01*
X-632833D01*
G01X-634167Y-538883D02*
X-636167D01*
G01X-629533Y-542500D02*
Y-535500D01*
X-627867D01*
X-627200Y-535850D01*
X-626700Y-536317D01*
X-626283Y-537017D01*
X-625950Y-537833D01*
X-625867Y-539000D01*
X-625950Y-540167D01*
X-626283Y-540983D01*
X-626700Y-541684D01*
X-627200Y-542150D01*
X-627867Y-542500D01*
X-629533D01*
G01X-615100Y-535500D02*
X-613100D01*
G01X-614100D02*
Y-542500D01*
G01X-615100D02*
X-613100D01*
G01X-609217D02*
Y-535500D01*
X-605383Y-542500D01*
Y-535500D01*
G01X-872500Y-520500D02*
Y-527500D01*
G01X-874417Y-520500D02*
X-870583D01*
G01X-867450Y-527500D02*
Y-520500D01*
G01X-863950D02*
Y-527500D01*
G01Y-524000D02*
X-867450D01*
G01X-857233Y-527500D02*
X-860567D01*
Y-520500D01*
X-857233D01*
G01X-858567Y-523883D02*
X-860567D01*
G01X-846967Y-527500D02*
Y-520500D01*
X-844967D01*
X-844300Y-520850D01*
X-843800Y-521667D01*
X-843633Y-522600D01*
X-843800Y-523533D01*
X-844217Y-524233D01*
X-844967Y-524584D01*
X-846967D01*
G01X-840167Y-527500D02*
Y-520500D01*
X-838083D01*
X-837417Y-520850D01*
X-837000Y-521317D01*
X-836833Y-522250D01*
X-837000Y-523183D01*
X-837500Y-523767D01*
X-838083Y-524117D01*
X-840167D01*
G01X-838083D02*
X-836833Y-527500D01*
G01X-831700D02*
X-832367Y-527383D01*
X-832950Y-526917D01*
X-833450Y-526217D01*
X-833783Y-525400D01*
X-833950Y-524467D01*
Y-523533D01*
X-833783Y-522600D01*
X-833450Y-521783D01*
X-832950Y-521083D01*
X-832367Y-520617D01*
X-831700Y-520500D01*
X-831033Y-520617D01*
X-830450Y-521083D01*
X-829950Y-521783D01*
X-829617Y-522600D01*
X-829450Y-523533D01*
Y-524467D01*
X-829617Y-525400D01*
X-829950Y-526217D01*
X-830450Y-526917D01*
X-831033Y-527383D01*
X-831700Y-527500D01*
G01X-826567D02*
Y-520500D01*
X-824567D01*
X-823900Y-520850D01*
X-823400Y-521667D01*
X-823233Y-522600D01*
X-823400Y-523533D01*
X-823817Y-524233D01*
X-824567Y-524584D01*
X-826567D01*
G01X-819767Y-527500D02*
Y-520500D01*
X-817683D01*
X-817017Y-520850D01*
X-816600Y-521317D01*
X-816433Y-522250D01*
X-816600Y-523183D01*
X-817100Y-523767D01*
X-817683Y-524117D01*
X-819767D01*
G01X-817683D02*
X-816433Y-527500D01*
G01X-812300Y-520500D02*
X-810300D01*
G01X-811300D02*
Y-527500D01*
G01X-812300D02*
X-810300D01*
G01X-802833D02*
X-806167D01*
Y-520500D01*
X-802833D01*
G01X-804167Y-523883D02*
X-806167D01*
G01X-797700Y-520500D02*
Y-527500D01*
G01X-799617Y-520500D02*
X-795783D01*
G01X-792983Y-527500D02*
X-790900Y-520500D01*
X-788817Y-527500D01*
G01X-789567Y-525050D02*
X-792233D01*
G01X-785767Y-527500D02*
Y-520500D01*
X-783683D01*
X-783017Y-520850D01*
X-782600Y-521317D01*
X-782433Y-522250D01*
X-782600Y-523183D01*
X-783100Y-523767D01*
X-783683Y-524117D01*
X-785767D01*
G01X-783683D02*
X-782433Y-527500D01*
G01X-777300D02*
Y-524350D01*
X-778967Y-520500D01*
G01X-775633D02*
X-777300Y-524350D01*
G01X-765367Y-527500D02*
Y-520500D01*
X-763367D01*
X-762700Y-520850D01*
X-762200Y-521667D01*
X-762033Y-522600D01*
X-762200Y-523533D01*
X-762617Y-524233D01*
X-763367Y-524584D01*
X-765367D01*
G01X-758567Y-527500D02*
Y-520500D01*
X-756483D01*
X-755817Y-520850D01*
X-755400Y-521317D01*
X-755233Y-522250D01*
X-755400Y-523183D01*
X-755900Y-523767D01*
X-756483Y-524117D01*
X-758567D01*
G01X-756483D02*
X-755233Y-527500D01*
G01X-750100D02*
X-750767Y-527383D01*
X-751350Y-526917D01*
X-751850Y-526217D01*
X-752183Y-525400D01*
X-752350Y-524467D01*
Y-523533D01*
X-752183Y-522600D01*
X-751850Y-521783D01*
X-751350Y-521083D01*
X-750767Y-520617D01*
X-750100Y-520500D01*
X-749433Y-520617D01*
X-748850Y-521083D01*
X-748350Y-521783D01*
X-748017Y-522600D01*
X-747850Y-523533D01*
Y-524467D01*
X-748017Y-525400D01*
X-748350Y-526217D01*
X-748850Y-526917D01*
X-749433Y-527383D01*
X-750100Y-527500D01*
G01X-744967D02*
Y-520500D01*
X-742967D01*
X-742300Y-520850D01*
X-741800Y-521667D01*
X-741633Y-522600D01*
X-741800Y-523533D01*
X-742217Y-524233D01*
X-742967Y-524584D01*
X-744967D01*
G01X-734833Y-527500D02*
X-738167D01*
Y-520500D01*
X-734833D01*
G01X-736167Y-523883D02*
X-738167D01*
G01X-731367Y-527500D02*
Y-520500D01*
X-729283D01*
X-728617Y-520850D01*
X-728200Y-521317D01*
X-728033Y-522250D01*
X-728200Y-523183D01*
X-728700Y-523767D01*
X-729283Y-524117D01*
X-731367D01*
G01X-729283D02*
X-728033Y-527500D01*
G01X-722900Y-520500D02*
Y-527500D01*
G01X-724817Y-520500D02*
X-720983D01*
G01X-716100Y-527500D02*
Y-524350D01*
X-717767Y-520500D01*
G01X-714433D02*
X-716100Y-524350D01*
G01X-702500Y-527500D02*
X-703167Y-527383D01*
X-703750Y-526917D01*
X-704250Y-526217D01*
X-704583Y-525400D01*
X-704750Y-524467D01*
Y-523533D01*
X-704583Y-522600D01*
X-704250Y-521783D01*
X-703750Y-521083D01*
X-703167Y-520617D01*
X-702500Y-520500D01*
X-701833Y-520617D01*
X-701250Y-521083D01*
X-700750Y-521783D01*
X-700417Y-522600D01*
X-700250Y-523533D01*
Y-524467D01*
X-700417Y-525400D01*
X-700750Y-526217D01*
X-701250Y-526917D01*
X-701833Y-527383D01*
X-702500Y-527500D01*
G01X-697283D02*
Y-520500D01*
X-694117D01*
G01X-695283Y-523883D02*
X-697283D01*
G01X-684267Y-527500D02*
Y-520500D01*
X-682100Y-526333D01*
X-679933Y-520500D01*
Y-527500D01*
G01X-676300Y-520500D02*
X-674300D01*
G01X-675300D02*
Y-527500D01*
G01X-676300D02*
X-674300D01*
G01X-666667Y-521083D02*
X-667167Y-520733D01*
X-667750Y-520500D01*
X-668417D01*
X-669167Y-520850D01*
X-669750Y-521433D01*
X-670167Y-522133D01*
X-670500Y-523300D01*
X-670583Y-524350D01*
X-670417Y-525400D01*
X-670167Y-526100D01*
X-669667Y-526800D01*
X-669083Y-527267D01*
X-668500Y-527500D01*
X-667917D01*
X-667333Y-527267D01*
X-666833Y-526917D01*
X-666417Y-526450D01*
G01X-663367Y-527500D02*
Y-520500D01*
X-661283D01*
X-660617Y-520850D01*
X-660200Y-521317D01*
X-660033Y-522250D01*
X-660200Y-523183D01*
X-660700Y-523767D01*
X-661283Y-524117D01*
X-663367D01*
G01X-661283D02*
X-660033Y-527500D01*
G01X-654900D02*
X-655567Y-527383D01*
X-656150Y-526917D01*
X-656650Y-526217D01*
X-656983Y-525400D01*
X-657150Y-524467D01*
Y-523533D01*
X-656983Y-522600D01*
X-656650Y-521783D01*
X-656150Y-521083D01*
X-655567Y-520617D01*
X-654900Y-520500D01*
X-654233Y-520617D01*
X-653650Y-521083D01*
X-653150Y-521783D01*
X-652817Y-522600D01*
X-652650Y-523533D01*
Y-524467D01*
X-652817Y-525400D01*
X-653150Y-526217D01*
X-653650Y-526917D01*
X-654233Y-527383D01*
X-654900Y-527500D01*
G01X-649850Y-526567D02*
X-649183Y-527150D01*
X-648433Y-527500D01*
X-647767D01*
X-647100Y-527150D01*
X-646600Y-526567D01*
X-646350Y-525750D01*
X-646517Y-524933D01*
X-646933Y-524233D01*
X-647683Y-523767D01*
X-648683Y-523533D01*
X-649267Y-523067D01*
X-649517Y-522250D01*
X-649350Y-521433D01*
X-648933Y-520850D01*
X-648350Y-520500D01*
X-647767D01*
X-647183Y-520733D01*
X-646683Y-521317D01*
G01X-641300Y-527500D02*
X-641967Y-527383D01*
X-642550Y-526917D01*
X-643050Y-526217D01*
X-643383Y-525400D01*
X-643550Y-524467D01*
Y-523533D01*
X-643383Y-522600D01*
X-643050Y-521783D01*
X-642550Y-521083D01*
X-641967Y-520617D01*
X-641300Y-520500D01*
X-640633Y-520617D01*
X-640050Y-521083D01*
X-639550Y-521783D01*
X-639217Y-522600D01*
X-639050Y-523533D01*
Y-524467D01*
X-639217Y-525400D01*
X-639550Y-526217D01*
X-640050Y-526917D01*
X-640633Y-527383D01*
X-641300Y-527500D01*
G01X-636083D02*
Y-520500D01*
X-632917D01*
G01X-634083Y-523883D02*
X-636083D01*
G01X-627700Y-520500D02*
Y-527500D01*
G01X-629617Y-520500D02*
X-625783D01*
G01X-872500Y-505500D02*
Y-512500D01*
G01X-874417Y-505500D02*
X-870583D01*
G01X-867450Y-512500D02*
Y-505500D01*
G01X-863950D02*
Y-512500D01*
G01Y-509000D02*
X-867450D01*
G01X-859900Y-505500D02*
X-857900D01*
G01X-858900D02*
Y-512500D01*
G01X-859900D02*
X-857900D01*
G01X-853850Y-511567D02*
X-853183Y-512150D01*
X-852433Y-512500D01*
X-851767D01*
X-851100Y-512150D01*
X-850600Y-511567D01*
X-850350Y-510750D01*
X-850517Y-509933D01*
X-850933Y-509233D01*
X-851683Y-508767D01*
X-852683Y-508533D01*
X-853267Y-508067D01*
X-853517Y-507250D01*
X-853350Y-506433D01*
X-852933Y-505850D01*
X-852350Y-505500D01*
X-851767D01*
X-851183Y-505733D01*
X-850683Y-506317D01*
G01X-840333Y-512500D02*
Y-505500D01*
X-838667D01*
X-838000Y-505850D01*
X-837500Y-506317D01*
X-837083Y-507017D01*
X-836750Y-507833D01*
X-836667Y-509000D01*
X-836750Y-510167D01*
X-837083Y-510983D01*
X-837500Y-511684D01*
X-838000Y-512150D01*
X-838667Y-512500D01*
X-840333D01*
G01X-833367D02*
Y-505500D01*
X-831283D01*
X-830617Y-505850D01*
X-830200Y-506317D01*
X-830033Y-507250D01*
X-830200Y-508183D01*
X-830700Y-508767D01*
X-831283Y-509117D01*
X-833367D01*
G01X-831283D02*
X-830033Y-512500D01*
G01X-826983D02*
X-824900Y-505500D01*
X-822817Y-512500D01*
G01X-823567Y-510050D02*
X-826233D01*
G01X-820600Y-505500D02*
X-819433Y-512500D01*
X-818100Y-505500D01*
X-816767Y-512500D01*
X-815600Y-505500D01*
G01X-812300D02*
X-810300D01*
G01X-811300D02*
Y-512500D01*
G01X-812300D02*
X-810300D01*
G01X-806417D02*
Y-505500D01*
X-802583Y-512500D01*
Y-505500D01*
G01X-797200Y-509000D02*
X-795533D01*
Y-511100D01*
X-796033Y-511800D01*
X-796617Y-512267D01*
X-797450Y-512500D01*
X-798283Y-512267D01*
X-798867Y-511800D01*
X-799367Y-511100D01*
X-799700Y-510283D01*
X-799867Y-509350D01*
Y-508533D01*
X-799700Y-507833D01*
X-799367Y-507017D01*
X-798867Y-506317D01*
X-798367Y-505850D01*
X-797700Y-505500D01*
X-797117D01*
X-796450Y-505733D01*
X-795950Y-506200D01*
G01X-782267Y-506083D02*
X-782767Y-505733D01*
X-783350Y-505500D01*
X-784017D01*
X-784767Y-505850D01*
X-785350Y-506433D01*
X-785767Y-507133D01*
X-786100Y-508300D01*
X-786183Y-509350D01*
X-786017Y-510400D01*
X-785767Y-511100D01*
X-785267Y-511800D01*
X-784683Y-512267D01*
X-784100Y-512500D01*
X-783517D01*
X-782933Y-512267D01*
X-782433Y-511917D01*
X-782017Y-511450D01*
G01X-777300Y-512500D02*
X-777967Y-512383D01*
X-778550Y-511917D01*
X-779050Y-511217D01*
X-779383Y-510400D01*
X-779550Y-509467D01*
Y-508533D01*
X-779383Y-507600D01*
X-779050Y-506783D01*
X-778550Y-506083D01*
X-777967Y-505617D01*
X-777300Y-505500D01*
X-776633Y-505617D01*
X-776050Y-506083D01*
X-775550Y-506783D01*
X-775217Y-507600D01*
X-775050Y-508533D01*
Y-509467D01*
X-775217Y-510400D01*
X-775550Y-511217D01*
X-776050Y-511917D01*
X-776633Y-512383D01*
X-777300Y-512500D01*
G01X-772417D02*
Y-505500D01*
X-768583Y-512500D01*
Y-505500D01*
G01X-763700D02*
Y-512500D01*
G01X-765617Y-505500D02*
X-761783D01*
G01X-758983Y-512500D02*
X-756900Y-505500D01*
X-754817Y-512500D01*
G01X-755567Y-510050D02*
X-758233D01*
G01X-751100Y-505500D02*
X-749100D01*
G01X-750100D02*
Y-512500D01*
G01X-751100D02*
X-749100D01*
G01X-745217D02*
Y-505500D01*
X-741383Y-512500D01*
Y-505500D01*
G01X-738250Y-511567D02*
X-737583Y-512150D01*
X-736833Y-512500D01*
X-736167D01*
X-735500Y-512150D01*
X-735000Y-511567D01*
X-734750Y-510750D01*
X-734917Y-509933D01*
X-735333Y-509233D01*
X-736083Y-508767D01*
X-737083Y-508533D01*
X-737667Y-508067D01*
X-737917Y-507250D01*
X-737750Y-506433D01*
X-737333Y-505850D01*
X-736750Y-505500D01*
X-736167D01*
X-735583Y-505733D01*
X-735083Y-506317D01*
G01X-723900Y-505500D02*
X-721900D01*
G01X-722900D02*
Y-512500D01*
G01X-723900D02*
X-721900D01*
G01X-718017D02*
Y-505500D01*
X-714183Y-512500D01*
Y-505500D01*
G01X-710883Y-512500D02*
Y-505500D01*
X-707717D01*
G01X-708883Y-508883D02*
X-710883D01*
G01X-702500Y-512500D02*
X-703167Y-512383D01*
X-703750Y-511917D01*
X-704250Y-511217D01*
X-704583Y-510400D01*
X-704750Y-509467D01*
Y-508533D01*
X-704583Y-507600D01*
X-704250Y-506783D01*
X-703750Y-506083D01*
X-703167Y-505617D01*
X-702500Y-505500D01*
X-701833Y-505617D01*
X-701250Y-506083D01*
X-700750Y-506783D01*
X-700417Y-507600D01*
X-700250Y-508533D01*
Y-509467D01*
X-700417Y-510400D01*
X-700750Y-511217D01*
X-701250Y-511917D01*
X-701833Y-512383D01*
X-702500Y-512500D01*
G01X-697367D02*
Y-505500D01*
X-695283D01*
X-694617Y-505850D01*
X-694200Y-506317D01*
X-694033Y-507250D01*
X-694200Y-508183D01*
X-694700Y-508767D01*
X-695283Y-509117D01*
X-697367D01*
G01X-695283D02*
X-694033Y-512500D01*
G01X-691067D02*
Y-505500D01*
X-688900Y-511333D01*
X-686733Y-505500D01*
Y-512500D01*
G01X-684183D02*
X-682100Y-505500D01*
X-680017Y-512500D01*
G01X-680767Y-510050D02*
X-683433D01*
G01X-675300Y-505500D02*
Y-512500D01*
G01X-677217Y-505500D02*
X-673383D01*
G01X-669500D02*
X-667500D01*
G01X-668500D02*
Y-512500D01*
G01X-669500D02*
X-667500D01*
G01X-661700D02*
X-662367Y-512383D01*
X-662950Y-511917D01*
X-663450Y-511217D01*
X-663783Y-510400D01*
X-663950Y-509467D01*
Y-508533D01*
X-663783Y-507600D01*
X-663450Y-506783D01*
X-662950Y-506083D01*
X-662367Y-505617D01*
X-661700Y-505500D01*
X-661033Y-505617D01*
X-660450Y-506083D01*
X-659950Y-506783D01*
X-659617Y-507600D01*
X-659450Y-508533D01*
Y-509467D01*
X-659617Y-510400D01*
X-659950Y-511217D01*
X-660450Y-511917D01*
X-661033Y-512383D01*
X-661700Y-512500D01*
G01X-656817D02*
Y-505500D01*
X-652983Y-512500D01*
Y-505500D01*
G01X-643800D02*
X-642633Y-512500D01*
X-641300Y-505500D01*
X-639967Y-512500D01*
X-638800Y-505500D01*
G01X-636250Y-512500D02*
Y-505500D01*
G01X-632750D02*
Y-512500D01*
G01Y-509000D02*
X-636250D01*
G01X-628700Y-505500D02*
X-626700D01*
G01X-627700D02*
Y-512500D01*
G01X-628700D02*
X-626700D01*
G01X-619067Y-506083D02*
X-619567Y-505733D01*
X-620150Y-505500D01*
X-620817D01*
X-621567Y-505850D01*
X-622150Y-506433D01*
X-622567Y-507133D01*
X-622900Y-508300D01*
X-622983Y-509350D01*
X-622817Y-510400D01*
X-622567Y-511100D01*
X-622067Y-511800D01*
X-621483Y-512267D01*
X-620900Y-512500D01*
X-620317D01*
X-619733Y-512267D01*
X-619233Y-511917D01*
X-618817Y-511450D01*
G01X-615850Y-512500D02*
Y-505500D01*
G01X-612350D02*
Y-512500D01*
G01Y-509000D02*
X-615850D01*
G01X-601500Y-505500D02*
X-599500D01*
G01X-600500D02*
Y-512500D01*
G01X-601500D02*
X-599500D01*
G01X-595450Y-511567D02*
X-594783Y-512150D01*
X-594033Y-512500D01*
X-593367D01*
X-592700Y-512150D01*
X-592200Y-511567D01*
X-591950Y-510750D01*
X-592117Y-509933D01*
X-592533Y-509233D01*
X-593283Y-508767D01*
X-594283Y-508533D01*
X-594867Y-508067D01*
X-595117Y-507250D01*
X-594950Y-506433D01*
X-594533Y-505850D01*
X-593950Y-505500D01*
X-593367D01*
X-592783Y-505733D01*
X-592283Y-506317D01*
G01X-858133Y-452500D02*
Y-445500D01*
X-856467D01*
X-855800Y-445850D01*
X-855300Y-446317D01*
X-854883Y-447017D01*
X-854550Y-447833D01*
X-854467Y-449000D01*
X-854550Y-450167D01*
X-854883Y-450983D01*
X-855300Y-451684D01*
X-855800Y-452150D01*
X-856467Y-452500D01*
X-858133D01*
G01X-847833D02*
X-851167D01*
Y-445500D01*
X-847833D01*
G01X-849167Y-448883D02*
X-851167D01*
G01X-844450Y-451567D02*
X-843783Y-452150D01*
X-843033Y-452500D01*
X-842367D01*
X-841700Y-452150D01*
X-841200Y-451567D01*
X-840950Y-450750D01*
X-841117Y-449933D01*
X-841533Y-449233D01*
X-842283Y-448767D01*
X-843283Y-448533D01*
X-843867Y-448067D01*
X-844117Y-447250D01*
X-843950Y-446433D01*
X-843533Y-445850D01*
X-842950Y-445500D01*
X-842367D01*
X-841783Y-445733D01*
X-841283Y-446317D01*
G01X-836900Y-445500D02*
X-834900D01*
G01X-835900D02*
Y-452500D01*
G01X-836900D02*
X-834900D01*
G01X-828600Y-449000D02*
X-826933D01*
Y-451100D01*
X-827433Y-451800D01*
X-828017Y-452267D01*
X-828850Y-452500D01*
X-829683Y-452267D01*
X-830267Y-451800D01*
X-830767Y-451100D01*
X-831100Y-450283D01*
X-831267Y-449350D01*
Y-448533D01*
X-831100Y-447833D01*
X-830767Y-447017D01*
X-830267Y-446317D01*
X-829767Y-445850D01*
X-829100Y-445500D01*
X-828517D01*
X-827850Y-445733D01*
X-827350Y-446200D01*
G01X-824217Y-452500D02*
Y-445500D01*
X-820383Y-452500D01*
Y-445500D01*
G01X-813833Y-452500D02*
X-817167D01*
Y-445500D01*
X-813833D01*
G01X-815167Y-448883D02*
X-817167D01*
G01X-810367Y-452500D02*
Y-445500D01*
X-808283D01*
X-807617Y-445850D01*
X-807200Y-446317D01*
X-807033Y-447250D01*
X-807200Y-448183D01*
X-807700Y-448767D01*
X-808283Y-449117D01*
X-810367D01*
G01X-808283D02*
X-807033Y-452500D01*
G01X-858133D02*
Y-445500D01*
X-856467D01*
X-855800Y-445850D01*
X-855300Y-446317D01*
X-854883Y-447017D01*
X-854550Y-447833D01*
X-854467Y-449000D01*
X-854550Y-450167D01*
X-854883Y-450983D01*
X-855300Y-451684D01*
X-855800Y-452150D01*
X-856467Y-452500D01*
X-858133D01*
G01X-847833D02*
X-851167D01*
Y-445500D01*
X-847833D01*
G01X-849167Y-448883D02*
X-851167D01*
G01X-844450Y-451567D02*
X-843783Y-452150D01*
X-843033Y-452500D01*
X-842367D01*
X-841700Y-452150D01*
X-841200Y-451567D01*
X-840950Y-450750D01*
X-841117Y-449933D01*
X-841533Y-449233D01*
X-842283Y-448767D01*
X-843283Y-448533D01*
X-843867Y-448067D01*
X-844117Y-447250D01*
X-843950Y-446433D01*
X-843533Y-445850D01*
X-842950Y-445500D01*
X-842367D01*
X-841783Y-445733D01*
X-841283Y-446317D01*
G01X-836900Y-445500D02*
X-834900D01*
G01X-835900D02*
Y-452500D01*
G01X-836900D02*
X-834900D01*
G01X-828600Y-449000D02*
X-826933D01*
Y-451100D01*
X-827433Y-451800D01*
X-828017Y-452267D01*
X-828850Y-452500D01*
X-829683Y-452267D01*
X-830267Y-451800D01*
X-830767Y-451100D01*
X-831100Y-450283D01*
X-831267Y-449350D01*
Y-448533D01*
X-831100Y-447833D01*
X-830767Y-447017D01*
X-830267Y-446317D01*
X-829767Y-445850D01*
X-829100Y-445500D01*
X-828517D01*
X-827850Y-445733D01*
X-827350Y-446200D01*
G01X-824217Y-452500D02*
Y-445500D01*
X-820383Y-452500D01*
Y-445500D01*
G01X-813833Y-452500D02*
X-817167D01*
Y-445500D01*
X-813833D01*
G01X-815167Y-448883D02*
X-817167D01*
G01X-810367Y-452500D02*
Y-445500D01*
X-808283D01*
X-807617Y-445850D01*
X-807200Y-446317D01*
X-807033Y-447250D01*
X-807200Y-448183D01*
X-807700Y-448767D01*
X-808283Y-449117D01*
X-810367D01*
G01X-808283D02*
X-807033Y-452500D01*
G01X-642033Y-455000D02*
Y-448000D01*
X-640367D01*
X-639700Y-448350D01*
X-639200Y-448817D01*
X-638783Y-449517D01*
X-638450Y-450333D01*
X-638367Y-451500D01*
X-638450Y-452667D01*
X-638783Y-453483D01*
X-639200Y-454184D01*
X-639700Y-454650D01*
X-640367Y-455000D01*
X-642033D01*
G01X-635483D02*
X-633400Y-448000D01*
X-631317Y-455000D01*
G01X-632067Y-452550D02*
X-634733D01*
G01X-626600Y-448000D02*
Y-455000D01*
G01X-628517Y-448000D02*
X-624683D01*
G01X-618133Y-455000D02*
X-621467D01*
Y-448000D01*
X-618133D01*
G01X-619467Y-451383D02*
X-621467D01*
G54D18*
G01X-1020800Y-457700D02*
G02X-1020300Y-458200I0J-500D01*
G01Y-458400D01*
G02X-1020900Y-459000I-600J0D01*
G01X-1021300D01*
G01X-1021800Y-460500D02*
Y-457700D01*
X-1020600D01*
G01X-1018340Y-459100D02*
G03I-2660J0D01*
G01X-1020700D02*
X-1020200Y-460500D01*
M02*
